(kicad_sch (version 20230121) (generator eeschema)

  (paper "A3")

  (title_block
    (title "Data Center RDIMM DDR4 Tester")
    (date "2024-09-30")
    (rev "1.2.4")
    (company "Antmicro Ltd.")
    (comment 1 "www.antmicro.com")
    (comment 2 "Antmicro Ltd")
  )

  (junction (at 329.184 228.854) (diameter 0) (color 0 0 0 0)
  )
  (junction (at 324.485 107.95) (diameter 0) (color 0 0 0 0)
  )
  (junction (at 111.125 115.57) (diameter 0) (color 0 0 0 0)
  )
  (junction (at 244.475 120.65) (diameter 0) (color 0 0 0 0)
  )
  (junction (at 324.485 105.41) (diameter 0) (color 0 0 0 0)
  )
  (junction (at 327.66 92.71) (diameter 0) (color 0 0 0 0)
  )
  (junction (at 371.475 92.71) (diameter 0) (color 0 0 0 0)
  )
  (junction (at 118.11 113.03) (diameter 0) (color 0 0 0 0)
  )
  (junction (at 244.475 102.235) (diameter 0) (color 0 0 0 0)
  )
  (junction (at 224.79 243.205) (diameter 0) (color 0 0 0 0)
  )
  (junction (at 73.025 237.49) (diameter 0) (color 0 0 0 0)
  )
  (junction (at 261.62 118.11) (diameter 0) (color 0 0 0 0)
  )
  (junction (at 36.83 229.87) (diameter 0) (color 0 0 0 0)
  )
  (junction (at 128.905 110.49) (diameter 0) (color 0 0 0 0)
  )
  (junction (at 36.83 232.41) (diameter 0) (color 0 0 0 0)
  )
  (junction (at 120.015 113.03) (diameter 0) (color 0 0 0 0)
  )
  (junction (at 363.22 100.965) (diameter 0) (color 0 0 0 0)
  )
  (junction (at 55.245 229.87) (diameter 0) (color 0 0 0 0)
  )
  (junction (at 324.485 100.33) (diameter 0) (color 0 0 0 0)
  )
  (junction (at 36.83 240.03) (diameter 0) (color 0 0 0 0)
  )
  (junction (at 363.22 92.71) (diameter 0) (color 0 0 0 0)
  )
  (junction (at 324.485 111.76) (diameter 0) (color 0 0 0 0)
  )
  (junction (at 36.83 237.49) (diameter 0) (color 0 0 0 0)
  )
  (junction (at 120.015 88.9) (diameter 0) (color 0 0 0 0)
  )
  (junction (at 36.83 242.57) (diameter 0) (color 0 0 0 0)
  )
  (junction (at 371.475 100.965) (diameter 0) (color 0 0 0 0)
  )
  (junction (at 252.73 102.235) (diameter 0) (color 0 0 0 0)
  )
  (junction (at 226.06 262.89) (diameter 0) (color 0 0 0 0)
  )
  (junction (at 70.485 234.95) (diameter 0) (color 0 0 0 0)
  )
  (junction (at 252.73 123.19) (diameter 0) (color 0 0 0 0)
  )
  (junction (at 224.79 230.505) (diameter 0) (color 0 0 0 0)
  )
  (junction (at 111.125 88.9) (diameter 0) (color 0 0 0 0)
  )
  (junction (at 57.785 232.41) (diameter 0) (color 0 0 0 0)
  )
  (junction (at 324.485 114.3) (diameter 0) (color 0 0 0 0)
  )
  (junction (at 137.16 107.95) (diameter 0) (color 0 0 0 0)
  )
  (junction (at 36.83 234.95) (diameter 0) (color 0 0 0 0)
  )
  (junction (at 128.905 88.9) (diameter 0) (color 0 0 0 0)
  )

  (no_connect (at 50.165 242.57))
  (no_connect (at 62.865 250.19))
  (no_connect (at 65.405 250.19))
  (no_connect (at 50.165 240.03))

  (wire (pts (xy 111.125 88.9) (xy 111.125 92.075))
    (stroke (width 0) (type default))
  )
  (wire (pts (xy 47.625 102.87) (xy 50.165 102.87))
    (stroke (width 0) (type default))
  )
  (wire (pts (xy 40.005 242.57) (xy 36.83 242.57))
    (stroke (width 0) (type default))
  )
  (wire (pts (xy 73.025 250.19) (xy 73.025 237.49))
    (stroke (width 0) (type default))
  )
  (wire (pts (xy 36.83 234.95) (xy 36.83 237.49))
    (stroke (width 0) (type default))
  )
  (wire (pts (xy 244.475 120.65) (xy 285.75 120.65))
    (stroke (width 0) (type default))
  )
  (wire (pts (xy 50.165 227.33) (xy 55.245 227.33))
    (stroke (width 0) (type default))
  )
  (wire (pts (xy 57.785 250.19) (xy 57.785 232.41))
    (stroke (width 0) (type default))
  )
  (wire (pts (xy 285.75 97.79) (xy 280.67 97.79))
    (stroke (width 0) (type default))
  )
  (wire (pts (xy 70.485 250.19) (xy 70.485 234.95))
    (stroke (width 0) (type default))
  )
  (wire (pts (xy 142.875 102.87) (xy 104.775 102.87))
    (stroke (width 0) (type default))
  )
  (wire (pts (xy 324.485 97.79) (xy 324.485 100.33))
    (stroke (width 0) (type default))
  )
  (wire (pts (xy 285.75 95.25) (xy 280.67 95.25))
    (stroke (width 0) (type default))
  )
  (wire (pts (xy 226.06 262.89) (xy 233.68 262.89))
    (stroke (width 0) (type default))
  )
  (wire (pts (xy 50.165 102.87) (xy 50.165 106.045))
    (stroke (width 0) (type default))
  )
  (polyline (pts (xy 299.72 252.73) (xy 299.72 200.025))
    (stroke (width 0) (type default))
  )

  (wire (pts (xy 111.125 115.57) (xy 111.125 97.155))
    (stroke (width 0) (type default))
  )
  (polyline (pts (xy 255.143 228.854) (xy 284.988 228.854))
    (stroke (width 0.1016) (type solid))
  )
  (polyline (pts (xy 274.32 226.06) (xy 274.32 243.205))
    (stroke (width 0.1016) (type solid))
  )

  (wire (pts (xy 222.25 230.505) (xy 224.79 230.505))
    (stroke (width 0) (type default))
  )
  (wire (pts (xy 252.73 123.19) (xy 252.73 129.54))
    (stroke (width 0) (type default))
  )
  (wire (pts (xy 173.99 257.81) (xy 178.435 257.81))
    (stroke (width 0) (type default))
  )
  (wire (pts (xy 40.005 234.95) (xy 36.83 234.95))
    (stroke (width 0) (type default))
  )
  (wire (pts (xy 280.67 105.41) (xy 285.75 105.41))
    (stroke (width 0) (type default))
  )
  (wire (pts (xy 69.85 115.57) (xy 69.85 122.555))
    (stroke (width 0) (type default))
  )
  (wire (pts (xy 363.22 100.965) (xy 363.22 99.695))
    (stroke (width 0) (type default))
  )
  (wire (pts (xy 40.005 240.03) (xy 36.83 240.03))
    (stroke (width 0) (type default))
  )
  (wire (pts (xy 151.765 257.81) (xy 154.94 257.81))
    (stroke (width 0) (type default))
  )
  (wire (pts (xy 173.99 238.125) (xy 178.435 238.125))
    (stroke (width 0) (type default))
  )
  (wire (pts (xy 50.165 237.49) (xy 73.025 237.49))
    (stroke (width 0) (type default))
  )
  (wire (pts (xy 247.65 266.065) (xy 247.65 262.89))
    (stroke (width 0) (type default))
  )
  (wire (pts (xy 247.65 262.89) (xy 246.38 262.89))
    (stroke (width 0) (type default))
  )
  (wire (pts (xy 141.605 266.7) (xy 170.18 266.7))
    (stroke (width 0) (type default))
  )
  (wire (pts (xy 324.104 228.854) (xy 329.184 228.854))
    (stroke (width 0) (type default))
  )
  (wire (pts (xy 36.83 229.87) (xy 36.83 232.41))
    (stroke (width 0) (type default))
  )
  (wire (pts (xy 104.775 107.95) (xy 137.16 107.95))
    (stroke (width 0) (type default))
  )
  (wire (pts (xy 285.75 110.49) (xy 280.67 110.49))
    (stroke (width 0) (type default))
  )
  (wire (pts (xy 321.31 92.71) (xy 327.66 92.71))
    (stroke (width 0) (type default))
  )
  (wire (pts (xy 120.015 92.075) (xy 120.015 88.9))
    (stroke (width 0) (type default))
  )
  (wire (pts (xy 252.73 102.235) (xy 252.73 108.585))
    (stroke (width 0) (type default))
  )
  (wire (pts (xy 128.905 88.9) (xy 137.16 88.9))
    (stroke (width 0) (type default))
  )
  (wire (pts (xy 78.105 247.65) (xy 82.55 247.65))
    (stroke (width 0) (type default))
  )
  (wire (pts (xy 69.215 102.87) (xy 73.66 102.87))
    (stroke (width 0) (type default))
  )
  (wire (pts (xy 327.66 78.74) (xy 327.66 83.185))
    (stroke (width 0) (type default))
  )
  (wire (pts (xy 240.03 102.235) (xy 244.475 102.235))
    (stroke (width 0) (type default))
  )
  (wire (pts (xy 161.29 257.81) (xy 160.02 257.81))
    (stroke (width 0) (type default))
  )
  (wire (pts (xy 321.31 111.76) (xy 324.485 111.76))
    (stroke (width 0) (type default))
  )
  (wire (pts (xy 261.62 118.11) (xy 285.75 118.11))
    (stroke (width 0) (type default))
  )
  (wire (pts (xy 36.83 242.57) (xy 36.83 247.015))
    (stroke (width 0) (type default))
  )
  (wire (pts (xy 365.76 228.854) (xy 378.46 228.854))
    (stroke (width 0) (type default))
  )
  (wire (pts (xy 324.485 107.95) (xy 321.31 107.95))
    (stroke (width 0) (type default))
  )
  (wire (pts (xy 371.475 100.965) (xy 378.46 100.965))
    (stroke (width 0) (type default))
  )
  (wire (pts (xy 93.98 110.49) (xy 99.695 110.49))
    (stroke (width 0) (type default))
  )
  (wire (pts (xy 285.75 113.03) (xy 280.67 113.03))
    (stroke (width 0) (type default))
  )
  (wire (pts (xy 118.11 113.03) (xy 118.11 117.475))
    (stroke (width 0) (type default))
  )
  (wire (pts (xy 244.475 108.585) (xy 244.475 102.235))
    (stroke (width 0) (type default))
  )
  (wire (pts (xy 40.005 229.87) (xy 36.83 229.87))
    (stroke (width 0) (type default))
  )
  (wire (pts (xy 50.165 229.87) (xy 55.245 229.87))
    (stroke (width 0) (type default))
  )
  (wire (pts (xy 50.165 234.95) (xy 70.485 234.95))
    (stroke (width 0) (type default))
  )
  (wire (pts (xy 141.605 247.015) (xy 170.18 247.015))
    (stroke (width 0) (type default))
  )
  (wire (pts (xy 235.585 243.205) (xy 240.665 243.205))
    (stroke (width 0) (type default))
  )
  (wire (pts (xy 170.18 266.7) (xy 170.18 265.43))
    (stroke (width 0) (type default))
  )
  (wire (pts (xy 324.485 97.79) (xy 321.31 97.79))
    (stroke (width 0) (type default))
  )
  (wire (pts (xy 118.11 113.03) (xy 120.015 113.03))
    (stroke (width 0) (type default))
  )
  (wire (pts (xy 363.22 100.965) (xy 363.22 104.14))
    (stroke (width 0) (type default))
  )
  (wire (pts (xy 73.66 115.57) (xy 69.85 115.57))
    (stroke (width 0) (type default))
  )
  (wire (pts (xy 324.485 78.74) (xy 327.66 78.74))
    (stroke (width 0) (type default))
  )
  (polyline (pts (xy 12.065 200.025) (xy 408.305 200.025))
    (stroke (width 0) (type default))
  )

  (wire (pts (xy 261.62 108.585) (xy 261.62 102.235))
    (stroke (width 0) (type default))
  )
  (wire (pts (xy 378.46 99.695) (xy 378.46 100.965))
    (stroke (width 0) (type default))
  )
  (wire (pts (xy 104.775 105.41) (xy 142.875 105.41))
    (stroke (width 0) (type default))
  )
  (wire (pts (xy 111.125 88.9) (xy 120.015 88.9))
    (stroke (width 0) (type default))
  )
  (wire (pts (xy 222.885 252.095) (xy 226.06 252.095))
    (stroke (width 0) (type default))
  )
  (wire (pts (xy 128.905 88.9) (xy 128.905 92.075))
    (stroke (width 0) (type default))
  )
  (wire (pts (xy 36.83 227.33) (xy 36.83 229.87))
    (stroke (width 0) (type default))
  )
  (wire (pts (xy 326.898 217.17) (xy 329.184 217.17))
    (stroke (width 0) (type default))
  )
  (wire (pts (xy 55.245 227.33) (xy 55.245 222.885))
    (stroke (width 0) (type default))
  )
  (wire (pts (xy 285.75 107.95) (xy 280.67 107.95))
    (stroke (width 0) (type default))
  )
  (wire (pts (xy 104.775 113.03) (xy 118.11 113.03))
    (stroke (width 0) (type default))
  )
  (wire (pts (xy 161.29 238.125) (xy 160.02 238.125))
    (stroke (width 0) (type default))
  )
  (wire (pts (xy 141.605 257.81) (xy 144.145 257.81))
    (stroke (width 0) (type default))
  )
  (wire (pts (xy 371.475 92.71) (xy 378.46 92.71))
    (stroke (width 0) (type default))
  )
  (wire (pts (xy 324.485 100.33) (xy 324.485 105.41))
    (stroke (width 0) (type default))
  )
  (wire (pts (xy 128.905 110.49) (xy 128.905 97.155))
    (stroke (width 0) (type default))
  )
  (wire (pts (xy 40.005 227.33) (xy 36.83 227.33))
    (stroke (width 0) (type default))
  )
  (wire (pts (xy 324.485 107.95) (xy 324.485 111.76))
    (stroke (width 0) (type default))
  )
  (wire (pts (xy 363.22 92.71) (xy 371.475 92.71))
    (stroke (width 0) (type default))
  )
  (wire (pts (xy 329.184 224.536) (xy 329.184 228.854))
    (stroke (width 0) (type default))
  )
  (wire (pts (xy 224.79 243.205) (xy 230.505 243.205))
    (stroke (width 0) (type default))
  )
  (wire (pts (xy 261.62 102.235) (xy 252.73 102.235))
    (stroke (width 0) (type default))
  )
  (wire (pts (xy 363.22 100.965) (xy 371.475 100.965))
    (stroke (width 0) (type default))
  )
  (polyline (pts (xy 112.395 285.115) (xy 112.395 200.025))
    (stroke (width 0) (type default))
  )

  (wire (pts (xy 40.005 232.41) (xy 36.83 232.41))
    (stroke (width 0) (type default))
  )
  (wire (pts (xy 107.315 88.9) (xy 111.125 88.9))
    (stroke (width 0) (type default))
  )
  (wire (pts (xy 93.98 115.57) (xy 99.695 115.57))
    (stroke (width 0) (type default))
  )
  (wire (pts (xy 36.83 240.03) (xy 36.83 242.57))
    (stroke (width 0) (type default))
  )
  (wire (pts (xy 371.475 92.71) (xy 371.475 94.615))
    (stroke (width 0) (type default))
  )
  (wire (pts (xy 137.16 92.075) (xy 137.16 88.9))
    (stroke (width 0) (type default))
  )
  (wire (pts (xy 222.885 262.89) (xy 226.06 262.89))
    (stroke (width 0) (type default))
  )
  (wire (pts (xy 93.98 102.87) (xy 99.695 102.87))
    (stroke (width 0) (type default))
  )
  (wire (pts (xy 240.665 235.585) (xy 235.585 235.585))
    (stroke (width 0) (type default))
  )
  (wire (pts (xy 137.16 97.155) (xy 137.16 107.95))
    (stroke (width 0) (type default))
  )
  (wire (pts (xy 378.46 94.615) (xy 378.46 92.71))
    (stroke (width 0) (type default))
  )
  (wire (pts (xy 78.105 250.19) (xy 78.105 247.65))
    (stroke (width 0) (type default))
  )
  (wire (pts (xy 329.184 228.854) (xy 336.804 228.854))
    (stroke (width 0) (type default))
  )
  (wire (pts (xy 36.83 237.49) (xy 36.83 240.03))
    (stroke (width 0) (type default))
  )
  (wire (pts (xy 230.505 248.285) (xy 224.79 248.285))
    (stroke (width 0) (type default))
  )
  (wire (pts (xy 244.475 102.235) (xy 252.73 102.235))
    (stroke (width 0) (type default))
  )
  (wire (pts (xy 224.79 235.585) (xy 224.79 230.505))
    (stroke (width 0) (type default))
  )
  (polyline (pts (xy 195.58 12.7) (xy 195.58 285.115))
    (stroke (width 0) (type default))
  )

  (wire (pts (xy 261.62 113.665) (xy 261.62 118.11))
    (stroke (width 0) (type default))
  )
  (wire (pts (xy 332.105 92.71) (xy 327.66 92.71))
    (stroke (width 0) (type default))
  )
  (wire (pts (xy 363.22 92.71) (xy 363.22 94.615))
    (stroke (width 0) (type default))
  )
  (wire (pts (xy 244.475 113.665) (xy 244.475 120.65))
    (stroke (width 0) (type default))
  )
  (wire (pts (xy 240.03 118.11) (xy 261.62 118.11))
    (stroke (width 0) (type default))
  )
  (wire (pts (xy 252.73 113.665) (xy 252.73 123.19))
    (stroke (width 0) (type default))
  )
  (wire (pts (xy 360.045 92.71) (xy 363.22 92.71))
    (stroke (width 0) (type default))
  )
  (wire (pts (xy 57.785 232.41) (xy 78.74 232.41))
    (stroke (width 0) (type default))
  )
  (wire (pts (xy 55.245 250.19) (xy 55.245 229.87))
    (stroke (width 0) (type default))
  )
  (wire (pts (xy 329.184 217.17) (xy 329.184 219.456))
    (stroke (width 0) (type default))
  )
  (wire (pts (xy 224.79 230.505) (xy 230.505 230.505))
    (stroke (width 0) (type default))
  )
  (wire (pts (xy 329.184 231.902) (xy 329.184 228.854))
    (stroke (width 0) (type default))
  )
  (wire (pts (xy 55.245 222.885) (xy 58.42 222.885))
    (stroke (width 0) (type default))
  )
  (wire (pts (xy 230.505 235.585) (xy 224.79 235.585))
    (stroke (width 0) (type default))
  )
  (wire (pts (xy 141.605 238.125) (xy 144.145 238.125))
    (stroke (width 0) (type default))
  )
  (wire (pts (xy 226.06 259.08) (xy 226.06 262.89))
    (stroke (width 0) (type default))
  )
  (wire (pts (xy 324.485 100.33) (xy 321.31 100.33))
    (stroke (width 0) (type default))
  )
  (wire (pts (xy 104.775 110.49) (xy 128.905 110.49))
    (stroke (width 0) (type default))
  )
  (wire (pts (xy 151.765 238.125) (xy 154.94 238.125))
    (stroke (width 0) (type default))
  )
  (wire (pts (xy 324.485 105.41) (xy 321.31 105.41))
    (stroke (width 0) (type default))
  )
  (wire (pts (xy 120.015 113.03) (xy 142.875 113.03))
    (stroke (width 0) (type default))
  )
  (wire (pts (xy 40.005 237.49) (xy 36.83 237.49))
    (stroke (width 0) (type default))
  )
  (wire (pts (xy 324.485 105.41) (xy 324.485 107.95))
    (stroke (width 0) (type default))
  )
  (wire (pts (xy 324.485 114.3) (xy 321.31 114.3))
    (stroke (width 0) (type default))
  )
  (wire (pts (xy 280.67 87.63) (xy 285.75 87.63))
    (stroke (width 0) (type default))
  )
  (wire (pts (xy 36.83 232.41) (xy 36.83 234.95))
    (stroke (width 0) (type default))
  )
  (wire (pts (xy 235.585 230.505) (xy 240.665 230.505))
    (stroke (width 0) (type default))
  )
  (wire (pts (xy 324.485 114.3) (xy 324.485 127.635))
    (stroke (width 0) (type default))
  )
  (wire (pts (xy 170.18 247.015) (xy 170.18 245.745))
    (stroke (width 0) (type default))
  )
  (wire (pts (xy 371.475 99.695) (xy 371.475 100.965))
    (stroke (width 0) (type default))
  )
  (wire (pts (xy 285.75 92.71) (xy 280.67 92.71))
    (stroke (width 0) (type default))
  )
  (wire (pts (xy 70.485 234.95) (xy 78.74 234.95))
    (stroke (width 0) (type default))
  )
  (wire (pts (xy 73.025 237.49) (xy 78.74 237.49))
    (stroke (width 0) (type default))
  )
  (wire (pts (xy 137.16 107.95) (xy 142.875 107.95))
    (stroke (width 0) (type default))
  )
  (wire (pts (xy 224.79 248.285) (xy 224.79 243.205))
    (stroke (width 0) (type default))
  )
  (wire (pts (xy 226.06 252.095) (xy 226.06 254))
    (stroke (width 0) (type default))
  )
  (wire (pts (xy 142.875 110.49) (xy 128.905 110.49))
    (stroke (width 0) (type default))
  )
  (wire (pts (xy 252.73 123.19) (xy 285.75 123.19))
    (stroke (width 0) (type default))
  )
  (wire (pts (xy 252.73 123.19) (xy 240.665 123.19))
    (stroke (width 0) (type default))
  )
  (wire (pts (xy 327.66 92.71) (xy 327.66 88.265))
    (stroke (width 0) (type default))
  )
  (wire (pts (xy 93.98 105.41) (xy 99.695 105.41))
    (stroke (width 0) (type default))
  )
  (wire (pts (xy 55.245 229.87) (xy 78.74 229.87))
    (stroke (width 0) (type default))
  )
  (wire (pts (xy 104.775 115.57) (xy 111.125 115.57))
    (stroke (width 0) (type default))
  )
  (wire (pts (xy 120.015 88.9) (xy 128.905 88.9))
    (stroke (width 0) (type default))
  )
  (wire (pts (xy 222.25 243.205) (xy 224.79 243.205))
    (stroke (width 0) (type default))
  )
  (wire (pts (xy 111.125 115.57) (xy 142.875 115.57))
    (stroke (width 0) (type default))
  )
  (wire (pts (xy 93.98 107.95) (xy 99.695 107.95))
    (stroke (width 0) (type default))
  )
  (wire (pts (xy 240.665 248.285) (xy 235.585 248.285))
    (stroke (width 0) (type default))
  )
  (wire (pts (xy 285.75 100.33) (xy 280.67 100.33))
    (stroke (width 0) (type default))
  )
  (wire (pts (xy 50.165 232.41) (xy 57.785 232.41))
    (stroke (width 0) (type default))
  )
  (wire (pts (xy 120.015 97.155) (xy 120.015 113.03))
    (stroke (width 0) (type default))
  )
  (wire (pts (xy 324.485 111.76) (xy 324.485 114.3))
    (stroke (width 0) (type default))
  )
  (wire (pts (xy 93.98 113.03) (xy 99.695 113.03))
    (stroke (width 0) (type default))
  )
  (wire (pts (xy 240.665 120.65) (xy 244.475 120.65))
    (stroke (width 0) (type default))
  )

  (text "Configuration Modes" (at 220.98 211.455 0)
    (effects (font (size 2.9972 2.9972) (thickness 0.5994) bold) (justify left bottom))
  )
  (text "JTAG Connector\n" (at 41.275 210.185 0)
    (effects (font (size 2.9972 2.9972) (thickness 0.5994) bold) (justify left bottom))
  )
  (text "000\n001\n010\n100\n101\n110\n111" (at 274.955 243.205 0)
    (effects (font (size 1.27 1.27)) (justify left bottom))
  )
  (text "FPGA BANK 0" (at 286.385 55.245 0)
    (effects (font (size 2.9972 2.9972) (thickness 0.5994) bold) (justify left bottom))
  )
  (text "MODE[2:0]" (at 274.828 228.346 0)
    (effects (font (size 1.27 1.27)) (justify left bottom))
  )
  (text "Master SPI Quad (x4) configuration scheme" (at 24.13 24.765 0)
    (effects (font (size 2.9972 2.9972) (thickness 0.5994) bold) (justify left bottom))
  )
  (text "Config. mode" (at 256.032 228.346 0)
    (effects (font (size 1.27 1.27)) (justify left bottom))
  )
  (text "Compatible with Xilinx Platform Cable" (at 41.91 212.725 0)
    (effects (font (size 1.27 1.27)) (justify left bottom))
  )
  (text "Master Serial\nMaster SPI\nMaster BPI\nMaster SelectMAP\nJTAG\nSlave SelectMAP\nSlave Serial"
    (at 255.905 243.205 0)
    (effects (font (size 1.27 1.27)) (justify left bottom))
  )
  (text "For details, see UG470 p. 21" (at 221.615 214.63 0)
    (effects (font (size 1.27 1.27)) (justify left bottom))
  )
  (text "Probes" (at 344.17 210.82 0)
    (effects (font (size 2.9972 2.9972) (thickness 0.5994) bold) (justify left bottom))
  )
  (text "STATUS LEDs" (at 137.795 210.82 0)
    (effects (font (size 2.9972 2.9972) (thickness 0.5994) bold) (justify left bottom))
  )
  (text "Follows Figure 2-14 7 Series FPGAs Configuration User Guide\nUG470 (v1.13.1)"
    (at 24.765 32.385 0)
    (effects (font (size 2.0066 2.0066)) (justify left bottom))
  )
  (text "(Q)SPI flash" (at 80.645 50.165 0)
    (effects (font (size 2.9972 2.9972) (thickness 0.5994) bold) (justify left bottom))
  )

  (global_label "CCLK" (shape input) (at 142.875 113.03 0) (fields_autoplaced)
    (effects (font (size 1.27 1.27)) (justify left))
    (property "Intersheetrefs" "${INTERSHEET_REFS}" (at -12.7 7.62 0)
      (effects (font (size 1.27 1.27)) hide)
    )
  )
  (global_label "MODE0" (shape input) (at 280.67 107.95 180) (fields_autoplaced)
    (effects (font (size 1.27 1.27)) (justify right))
    (property "Intersheetrefs" "${INTERSHEET_REFS}" (at 4.445 -3.81 0)
      (effects (font (size 1.27 1.27)) hide)
    )
  )
  (global_label "TMS_JTAG" (shape input) (at 280.67 97.79 180) (fields_autoplaced)
    (effects (font (size 1.27 1.27)) (justify right))
    (property "Intersheetrefs" "${INTERSHEET_REFS}" (at 4.445 -3.81 0)
      (effects (font (size 1.27 1.27)) hide)
    )
  )
  (global_label "3V3_SYS" (shape input) (at 240.665 230.505 0) (fields_autoplaced)
    (effects (font (size 1.27 1.27)) (justify left))
    (property "Intersheetrefs" "${INTERSHEET_REFS}" (at 250.9788 230.505 0)
      (effects (font (size 1.27 1.27)) (justify left) hide)
    )
  )
  (global_label "QSPI_DQ2" (shape input) (at 142.875 107.95 0) (fields_autoplaced)
    (effects (font (size 1.27 1.27)) (justify left))
    (property "Intersheetrefs" "${INTERSHEET_REFS}" (at -12.065 -5.08 0)
      (effects (font (size 1.27 1.27)) hide)
    )
  )
  (global_label "3V3_SYS" (shape input) (at 240.665 243.205 0) (fields_autoplaced)
    (effects (font (size 1.27 1.27)) (justify left))
    (property "Intersheetrefs" "${INTERSHEET_REFS}" (at 250.9788 243.205 0)
      (effects (font (size 1.27 1.27)) (justify left) hide)
    )
  )
  (global_label "INIT_B" (shape input) (at 240.665 120.65 180) (fields_autoplaced)
    (effects (font (size 1.27 1.27)) (justify right))
    (property "Intersheetrefs" "${INTERSHEET_REFS}" (at 20.32 -3.81 0)
      (effects (font (size 1.27 1.27)) hide)
    )
  )
  (global_label "MODE1" (shape input) (at 222.25 243.205 180) (fields_autoplaced)
    (effects (font (size 1.27 1.27)) (justify right))
    (property "Intersheetrefs" "${INTERSHEET_REFS}" (at 213.5086 243.205 0)
      (effects (font (size 1.27 1.27)) (justify right) hide)
    )
  )
  (global_label "CCLK" (shape input) (at 280.67 105.41 180) (fields_autoplaced)
    (effects (font (size 1.27 1.27)) (justify right))
    (property "Intersheetrefs" "${INTERSHEET_REFS}" (at 4.445 -3.81 0)
      (effects (font (size 1.27 1.27)) hide)
    )
  )
  (global_label "FCS_B" (shape input) (at 142.875 115.57 0) (fields_autoplaced)
    (effects (font (size 1.27 1.27)) (justify left))
    (property "Intersheetrefs" "${INTERSHEET_REFS}" (at -12.7 12.7 0)
      (effects (font (size 1.27 1.27)) hide)
    )
  )
  (global_label "3V3_SYS" (shape input) (at 69.215 102.87 180) (fields_autoplaced)
    (effects (font (size 1.27 1.27)) (justify right))
    (property "Intersheetrefs" "${INTERSHEET_REFS}" (at -28.575 169.545 0)
      (effects (font (size 1.27 1.27)) hide)
    )
  )
  (global_label "PROGRAM_B" (shape input) (at 240.665 123.19 180) (fields_autoplaced)
    (effects (font (size 1.27 1.27)) (justify right))
    (property "Intersheetrefs" "${INTERSHEET_REFS}" (at 20.32 -3.81 0)
      (effects (font (size 1.27 1.27)) hide)
    )
  )
  (global_label "PUDC_B" (shape input) (at 336.804 228.854 0) (fields_autoplaced)
    (effects (font (size 1.27 1.27)) (justify left))
    (property "Intersheetrefs" "${INTERSHEET_REFS}" (at 5.334 -1.651 0)
      (effects (font (size 1.27 1.27)) hide)
    )
  )
  (global_label "CFGBVS" (shape input) (at 332.105 92.71 0) (fields_autoplaced)
    (effects (font (size 1.27 1.27)) (justify left))
    (property "Intersheetrefs" "${INTERSHEET_REFS}" (at 608.965 -39.37 0)
      (effects (font (size 1.27 1.27)) (justify left) hide)
    )
  )
  (global_label "3V3_SYS" (shape input) (at 141.605 238.125 180) (fields_autoplaced)
    (effects (font (size 1.27 1.27)) (justify right))
    (property "Intersheetrefs" "${INTERSHEET_REFS}" (at 131.2912 238.125 0)
      (effects (font (size 1.27 1.27)) (justify right) hide)
    )
  )
  (global_label "TCK_JTAG" (shape input) (at 280.67 100.33 180) (fields_autoplaced)
    (effects (font (size 1.27 1.27)) (justify right))
    (property "Intersheetrefs" "${INTERSHEET_REFS}" (at 4.445 -3.81 0)
      (effects (font (size 1.27 1.27)) hide)
    )
  )
  (global_label "TMS_JTAG" (shape input) (at 78.74 229.87 0) (fields_autoplaced)
    (effects (font (size 1.27 1.27)) (justify left))
    (property "Intersheetrefs" "${INTERSHEET_REFS}" (at 89.9609 229.87 0)
      (effects (font (size 1.27 1.27)) (justify left) hide)
    )
  )
  (global_label "MODE1" (shape input) (at 280.67 110.49 180) (fields_autoplaced)
    (effects (font (size 1.27 1.27)) (justify right))
    (property "Intersheetrefs" "${INTERSHEET_REFS}" (at 4.445 -3.81 0)
      (effects (font (size 1.27 1.27)) hide)
    )
  )
  (global_label "3V3_SYS" (shape input) (at 280.67 87.63 180) (fields_autoplaced)
    (effects (font (size 1.27 1.27)) (justify right))
    (property "Intersheetrefs" "${INTERSHEET_REFS}" (at 212.09 392.43 0)
      (effects (font (size 1.27 1.27)) hide)
    )
  )
  (global_label "3V3_SYS" (shape input) (at 141.605 257.81 180) (fields_autoplaced)
    (effects (font (size 1.27 1.27)) (justify right))
    (property "Intersheetrefs" "${INTERSHEET_REFS}" (at -0.635 0 0)
      (effects (font (size 1.27 1.27)) hide)
    )
  )
  (global_label "3V3_SYS" (shape input) (at 360.045 92.71 180) (fields_autoplaced)
    (effects (font (size 1.27 1.27)) (justify right))
    (property "Intersheetrefs" "${INTERSHEET_REFS}" (at 268.605 466.725 0)
      (effects (font (size 1.27 1.27)) hide)
    )
  )
  (global_label "MODE2" (shape input) (at 222.885 262.89 180) (fields_autoplaced)
    (effects (font (size 1.27 1.27)) (justify right))
    (property "Intersheetrefs" "${INTERSHEET_REFS}" (at 0 5.08 0)
      (effects (font (size 1.27 1.27)) hide)
    )
  )
  (global_label "3V3_SYS" (shape input) (at 222.885 252.095 180) (fields_autoplaced)
    (effects (font (size 1.27 1.27)) (justify right))
    (property "Intersheetrefs" "${INTERSHEET_REFS}" (at 464.185 504.19 0)
      (effects (font (size 1.27 1.27)) hide)
    )
  )
  (global_label "EMCCLK" (shape input) (at 378.46 228.854 0) (fields_autoplaced)
    (effects (font (size 1.27 1.27)) (justify left))
    (property "Intersheetrefs" "${INTERSHEET_REFS}" (at -5.715 -0.381 0)
      (effects (font (size 1.27 1.27)) hide)
    )
  )
  (global_label "3V3_SYS" (shape input) (at 240.03 102.235 180) (fields_autoplaced)
    (effects (font (size 1.27 1.27)) (justify right))
    (property "Intersheetrefs" "${INTERSHEET_REFS}" (at 137.795 349.25 0)
      (effects (font (size 1.27 1.27)) hide)
    )
  )
  (global_label "MODE2" (shape input) (at 280.67 113.03 180) (fields_autoplaced)
    (effects (font (size 1.27 1.27)) (justify right))
    (property "Intersheetrefs" "${INTERSHEET_REFS}" (at 4.445 -3.81 0)
      (effects (font (size 1.27 1.27)) hide)
    )
  )
  (global_label "3V3_SYS" (shape input) (at 326.898 217.17 180) (fields_autoplaced)
    (effects (font (size 1.27 1.27)) (justify right))
    (property "Intersheetrefs" "${INTERSHEET_REFS}" (at 110.998 541.02 0)
      (effects (font (size 1.27 1.27)) hide)
    )
  )
  (global_label "3V3_SYS" (shape input) (at 107.315 88.9 180) (fields_autoplaced)
    (effects (font (size 1.27 1.27)) (justify right))
    (property "Intersheetrefs" "${INTERSHEET_REFS}" (at 29.845 230.505 0)
      (effects (font (size 1.27 1.27)) hide)
    )
  )
  (global_label "DONE" (shape input) (at 141.605 247.015 180) (fields_autoplaced)
    (effects (font (size 1.27 1.27)) (justify right))
    (property "Intersheetrefs" "${INTERSHEET_REFS}" (at -2.54 1.27 0)
      (effects (font (size 1.27 1.27)) hide)
    )
  )
  (global_label "3V3_SYS" (shape input) (at 58.42 222.885 0) (fields_autoplaced)
    (effects (font (size 1.27 1.27)) (justify left))
    (property "Intersheetrefs" "${INTERSHEET_REFS}" (at 281.305 168.275 0)
      (effects (font (size 1.27 1.27)) hide)
    )
  )
  (global_label "INIT_B" (shape input) (at 141.605 266.7 180) (fields_autoplaced)
    (effects (font (size 1.27 1.27)) (justify right))
    (property "Intersheetrefs" "${INTERSHEET_REFS}" (at -3.175 1.27 0)
      (effects (font (size 1.27 1.27)) hide)
    )
  )
  (global_label "TDI_JTAG" (shape input) (at 78.74 237.49 0) (fields_autoplaced)
    (effects (font (size 1.27 1.27)) (justify left))
    (property "Intersheetrefs" "${INTERSHEET_REFS}" (at 89.1748 237.49 0)
      (effects (font (size 1.27 1.27)) (justify left) hide)
    )
  )
  (global_label "TCK_JTAG" (shape input) (at 78.74 232.41 0) (fields_autoplaced)
    (effects (font (size 1.27 1.27)) (justify left))
    (property "Intersheetrefs" "${INTERSHEET_REFS}" (at 89.84 232.41 0)
      (effects (font (size 1.27 1.27)) (justify left) hide)
    )
  )
  (global_label "MODE0" (shape input) (at 222.25 230.505 180) (fields_autoplaced)
    (effects (font (size 1.27 1.27)) (justify right))
    (property "Intersheetrefs" "${INTERSHEET_REFS}" (at 213.5086 230.505 0)
      (effects (font (size 1.27 1.27)) (justify right) hide)
    )
  )
  (global_label "3V3_SYS" (shape input) (at 324.485 78.74 180) (fields_autoplaced)
    (effects (font (size 1.27 1.27)) (justify right))
    (property "Intersheetrefs" "${INTERSHEET_REFS}" (at 255.905 -209.55 90)
      (effects (font (size 1.27 1.27)) (justify left) hide)
    )
  )
  (global_label "QSPI_DQ0" (shape input) (at 142.875 102.87 0) (fields_autoplaced)
    (effects (font (size 1.27 1.27)) (justify left))
    (property "Intersheetrefs" "${INTERSHEET_REFS}" (at -12.065 -15.24 0)
      (effects (font (size 1.27 1.27)) hide)
    )
  )
  (global_label "3V3_SYS" (shape input) (at 47.625 102.87 180) (fields_autoplaced)
    (effects (font (size 1.27 1.27)) (justify right))
    (property "Intersheetrefs" "${INTERSHEET_REFS}" (at -50.165 161.29 0)
      (effects (font (size 1.27 1.27)) hide)
    )
  )
  (global_label "DONE" (shape input) (at 240.03 118.11 180) (fields_autoplaced)
    (effects (font (size 1.27 1.27)) (justify right))
    (property "Intersheetrefs" "${INTERSHEET_REFS}" (at 20.32 -3.81 0)
      (effects (font (size 1.27 1.27)) hide)
    )
  )
  (global_label "TDI_JTAG" (shape input) (at 280.67 92.71 180) (fields_autoplaced)
    (effects (font (size 1.27 1.27)) (justify right))
    (property "Intersheetrefs" "${INTERSHEET_REFS}" (at 4.445 -3.81 0)
      (effects (font (size 1.27 1.27)) hide)
    )
  )
  (global_label "QSPI_DQ3" (shape input) (at 142.875 110.49 0) (fields_autoplaced)
    (effects (font (size 1.27 1.27)) (justify left))
    (property "Intersheetrefs" "${INTERSHEET_REFS}" (at -12.065 0 0)
      (effects (font (size 1.27 1.27)) hide)
    )
  )
  (global_label "TDO_JTAG" (shape input) (at 280.67 95.25 180) (fields_autoplaced)
    (effects (font (size 1.27 1.27)) (justify right))
    (property "Intersheetrefs" "${INTERSHEET_REFS}" (at 4.445 -3.81 0)
      (effects (font (size 1.27 1.27)) hide)
    )
  )
  (global_label "TDO_JTAG" (shape input) (at 78.74 234.95 0) (fields_autoplaced)
    (effects (font (size 1.27 1.27)) (justify left))
    (property "Intersheetrefs" "${INTERSHEET_REFS}" (at 89.9005 234.95 0)
      (effects (font (size 1.27 1.27)) (justify left) hide)
    )
  )
  (global_label "QSPI_DQ1" (shape input) (at 142.875 105.41 0) (fields_autoplaced)
    (effects (font (size 1.27 1.27)) (justify left))
    (property "Intersheetrefs" "${INTERSHEET_REFS}" (at -12.065 -15.24 0)
      (effects (font (size 1.27 1.27)) hide)
    )
  )

  (symbol (lib_id "antmicropower:GND") (at 36.83 247.015 0) (unit 1)
    (in_bom yes) (on_board yes) (dnp no) (fields_autoplaced)
    (property "Reference" "#PWR0110" (at 36.83 253.365 0)
      (effects (font (size 1.27 1.27)) hide)
    )
    (property "Value" "GND" (at 36.83 251.46 0)
      (effects (font (size 1.27 1.27)))
    )
    (property "Footprint" "" (at 36.83 247.015 0)
      (effects (font (size 1.27 1.27)) hide)
    )
    (property "Datasheet" "" (at 36.83 247.015 0)
      (effects (font (size 1.27 1.27)) hide)
    )
    (property "Author" "Antmicro" (at 45.72 254.635 0)
      (effects (font (size 1.27 1.27) (thickness 0.15)) (justify left bottom) hide)
    )
    (property "License" "Apache-2.0" (at 45.72 257.175 0)
      (effects (font (size 1.27 1.27) (thickness 0.15)) (justify left bottom) hide)
    )
    (pin "1")
    (instances
      (project "data-center-rdimm-ddr4-tester"
        (path ""
          (reference "#PWR0110") (unit 1)
        )
      )
    )
  )

  (symbol (lib_id "antmicroTVSDiodes:TPD6E05U06RVZR") (at 55.245 250.19 90) (mirror x) (unit 1)
    (in_bom no) (on_board yes) (dnp yes)
    (property "Reference" "D4" (at 81.28 254 90)
      (effects (font (size 1.27 1.27)) (justify right))
    )
    (property "Value" "TPD6E05U06RVZR" (at 81.28 255.905 90)
      (effects (font (size 1.27 1.27) (thickness 0.15)) (justify right))
    )
    (property "Footprint" "antmicro-footprints:USON-14_3.5X1.3X0.5mm_P0.5mm" (at 60.325 273.05 0)
      (effects (font (size 1.27 1.27) (thickness 0.15)) (justify left bottom) hide)
    )
    (property "Datasheet" "http://www.ti.com/lit/ds/symlink/tpd6e05u06.pdf" (at 62.865 273.05 0)
      (effects (font (size 1.27 1.27) (thickness 0.15)) (justify left bottom) hide)
    )
    (property "MPN" "TPD6E05U06RVZR" (at 65.405 273.05 0)
      (effects (font (size 1.27 1.27) (thickness 0.15)) (justify left bottom) hide)
    )
    (property "Manufacturer" "Texas Instruments" (at 67.945 273.05 0)
      (effects (font (size 1.27 1.27) (thickness 0.15)) (justify left bottom) hide)
    )
    (property "Author" "Antmicro" (at 70.485 273.05 0)
      (effects (font (size 1.27 1.27) (thickness 0.15)) (justify left bottom) hide)
    )
    (property "License" "Apache-2.0" (at 73.025 273.05 0)
      (effects (font (size 1.27 1.27) (thickness 0.15)) (justify left bottom) hide)
    )
    (property "DNP" "DNP" (at 81.28 257.81 90)
      (effects (font (size 1.27 1.27)) (justify right))
    )
    (pin "1")
    (pin "2")
    (pin "3")
    (pin "4")
    (pin "6")
    (pin "7")
    (pin "10")
    (pin "11")
    (pin "12")
    (pin "13")
    (pin "14")
    (pin "5")
    (pin "8")
    (pin "9")
    (instances
      (project "data-center-rdimm-ddr4-tester"
        (path ""
          (reference "D4") (unit 1)
        )
      )
    )
  )

  (symbol (lib_id "antmicropower:GND") (at 82.55 247.65 90) (unit 1)
    (in_bom yes) (on_board yes) (dnp no) (fields_autoplaced)
    (property "Reference" "#PWR0111" (at 88.9 247.65 0)
      (effects (font (size 1.27 1.27)) hide)
    )
    (property "Value" "GND" (at 86.36 247.6499 90)
      (effects (font (size 1.27 1.27)) (justify right))
    )
    (property "Footprint" "" (at 82.55 247.65 0)
      (effects (font (size 1.27 1.27)) hide)
    )
    (property "Datasheet" "" (at 82.55 247.65 0)
      (effects (font (size 1.27 1.27)) hide)
    )
    (property "Author" "Antmicro" (at 90.17 238.76 0)
      (effects (font (size 1.27 1.27) (thickness 0.15)) (justify left bottom) hide)
    )
    (property "License" "Apache-2.0" (at 92.71 238.76 0)
      (effects (font (size 1.27 1.27) (thickness 0.15)) (justify left bottom) hide)
    )
    (pin "1")
    (instances
      (project "data-center-rdimm-ddr4-tester"
        (path ""
          (reference "#PWR0111") (unit 1)
        )
      )
    )
  )

  (symbol (lib_id "antmicroResistors0402:R_100R_0402") (at 118.11 117.475 270) (unit 1)
    (in_bom no) (on_board yes) (dnp yes)
    (property "Reference" "R34" (at 120.65 118.745 90)
      (effects (font (size 1.524 1.524)) (justify left))
    )
    (property "Value" "R_100R_0402" (at 105.41 137.795 0)
      (effects (font (size 1.27 1.27) (thickness 0.15)) (justify left bottom) hide)
    )
    (property "Footprint" "antmicro-footprints:R_0402_1005Metric" (at 102.87 137.795 0)
      (effects (font (size 1.27 1.27) (thickness 0.15)) (justify left bottom) hide)
    )
    (property "Datasheet" "https://www.bourns.com/docs/product-datasheets/cr.pdf" (at 100.33 137.795 0)
      (effects (font (size 1.27 1.27) (thickness 0.15)) (justify left bottom) hide)
    )
    (property "Manufacturer" "Bourns" (at 95.25 137.795 0)
      (effects (font (size 1.27 1.27) (thickness 0.15)) (justify left bottom) hide)
    )
    (property "MPN" "CR0402-FX-1000GLF" (at 97.79 137.795 0)
      (effects (font (size 1.27 1.27) (thickness 0.15)) (justify left bottom) hide)
    )
    (property "Val" "100R" (at 120.65 121.9199 90)
      (effects (font (size 1.27 1.27) (thickness 0.15)) (justify left))
    )
    (property "License" "Apache-2.0" (at 92.71 137.795 0)
      (effects (font (size 1.27 1.27) (thickness 0.15)) (justify left bottom) hide)
    )
    (property "Author" "Antmicro" (at 90.17 137.795 0)
      (effects (font (size 1.27 1.27) (thickness 0.15)) (justify left bottom) hide)
    )
    (property "Tolerance" "1%" (at 107.95 137.795 0)
      (effects (font (size 1.27 1.27)) (justify left bottom) hide)
    )
    (property "DNP" "DNP" (at 118.11 120.015 0)
      (effects (font (size 1.27 1.27)))
    )
    (pin "1")
    (pin "2")
    (instances
      (project "data-center-rdimm-ddr4-tester"
        (path ""
          (reference "R34") (unit 1)
        )
      )
    )
  )

  (symbol (lib_id "antmicroMemory:S25FL128SAGNFI000") (at 93.98 100.33 0) (mirror y) (unit 1)
    (in_bom yes) (on_board yes) (dnp no) (fields_autoplaced)
    (property "Reference" "U3" (at 83.82 93.98 0)
      (effects (font (size 1.524 1.524)))
    )
    (property "Value" "S25FL128SAGNFI000" (at 83.82 97.79 0)
      (effects (font (size 1.27 1.27) (thickness 0.15)))
    )
    (property "Footprint" "antmicro-footprints:WSON-8_6x8x0.5mm_P1.27mm" (at 48.26 107.95 0)
      (effects (font (size 1.27 1.27) (thickness 0.15)) (justify left bottom) hide)
    )
    (property "Datasheet" "https://www.farnell.com/datasheets/2309615.pdf" (at 48.26 110.49 0)
      (effects (font (size 1.27 1.27) (thickness 0.15)) (justify left bottom) hide)
    )
    (property "MPN" "S25FL128SAGNFI000" (at 48.26 115.57 0)
      (effects (font (size 1.27 1.27) (thickness 0.15)) (justify left bottom) hide)
    )
    (property "Manufacturer" "Cypress Semiconductor" (at 48.26 113.03 0)
      (effects (font (size 1.27 1.27) (thickness 0.15)) (justify left bottom) hide)
    )
    (property "Author" "Antmicro" (at 48.26 118.11 0)
      (effects (font (size 1.27 1.27) (thickness 0.15)) (justify left bottom) hide)
    )
    (property "License" "Apache-2.0" (at 48.26 120.65 0)
      (effects (font (size 1.27 1.27) (thickness 0.15)) (justify left bottom) hide)
    )
    (pin "1")
    (pin "2")
    (pin "3")
    (pin "4")
    (pin "5")
    (pin "6")
    (pin "7")
    (pin "8")
    (pin "9")
    (instances
      (project "data-center-rdimm-ddr4-tester"
        (path ""
          (reference "U3") (unit 1)
        )
      )
    )
  )

  (symbol (lib_id "antmicropower:GND") (at 69.85 122.555 0) (unit 1)
    (in_bom yes) (on_board yes) (dnp no) (fields_autoplaced)
    (property "Reference" "#PWR0104" (at 69.85 128.905 0)
      (effects (font (size 1.27 1.27)) hide)
    )
    (property "Value" "GND" (at 69.85 127.635 0)
      (effects (font (size 1.27 1.27)))
    )
    (property "Footprint" "" (at 69.85 122.555 0)
      (effects (font (size 1.27 1.27)) hide)
    )
    (property "Datasheet" "" (at 69.85 122.555 0)
      (effects (font (size 1.27 1.27)) hide)
    )
    (property "Author" "Antmicro" (at 78.74 130.175 0)
      (effects (font (size 1.27 1.27) (thickness 0.15)) (justify left bottom) hide)
    )
    (property "License" "Apache-2.0" (at 78.74 132.715 0)
      (effects (font (size 1.27 1.27) (thickness 0.15)) (justify left bottom) hide)
    )
    (pin "1")
    (instances
      (project "data-center-rdimm-ddr4-tester"
        (path ""
          (reference "#PWR0104") (unit 1)
        )
      )
    )
  )

  (symbol (lib_id "antmicropower:GND") (at 240.665 235.585 90) (unit 1)
    (in_bom yes) (on_board yes) (dnp no) (fields_autoplaced)
    (property "Reference" "#PWR0113" (at 247.015 235.585 0)
      (effects (font (size 1.27 1.27)) hide)
    )
    (property "Value" "GND" (at 243.84 235.5849 90)
      (effects (font (size 1.27 1.27)) (justify right))
    )
    (property "Footprint" "" (at 240.665 235.585 0)
      (effects (font (size 1.27 1.27)) hide)
    )
    (property "Datasheet" "" (at 240.665 235.585 0)
      (effects (font (size 1.27 1.27)) hide)
    )
    (property "Author" "Antmicro" (at 248.285 226.695 0)
      (effects (font (size 1.27 1.27) (thickness 0.15)) (justify left bottom) hide)
    )
    (property "License" "Apache-2.0" (at 250.825 226.695 0)
      (effects (font (size 1.27 1.27) (thickness 0.15)) (justify left bottom) hide)
    )
    (pin "1")
    (instances
      (project "data-center-rdimm-ddr4-tester"
        (path ""
          (reference "#PWR0113") (unit 1)
        )
      )
    )
  )

  (symbol (lib_id "antmicropower:GND") (at 240.665 248.285 90) (unit 1)
    (in_bom yes) (on_board yes) (dnp no) (fields_autoplaced)
    (property "Reference" "#PWR0114" (at 247.015 248.285 0)
      (effects (font (size 1.27 1.27)) hide)
    )
    (property "Value" "GND" (at 243.84 248.2849 90)
      (effects (font (size 1.27 1.27)) (justify right))
    )
    (property "Footprint" "" (at 240.665 248.285 0)
      (effects (font (size 1.27 1.27)) hide)
    )
    (property "Datasheet" "" (at 240.665 248.285 0)
      (effects (font (size 1.27 1.27)) hide)
    )
    (property "Author" "Antmicro" (at 248.285 239.395 0)
      (effects (font (size 1.27 1.27) (thickness 0.15)) (justify left bottom) hide)
    )
    (property "License" "Apache-2.0" (at 250.825 239.395 0)
      (effects (font (size 1.27 1.27) (thickness 0.15)) (justify left bottom) hide)
    )
    (pin "1")
    (instances
      (project "data-center-rdimm-ddr4-tester"
        (path ""
          (reference "#PWR0114") (unit 1)
        )
      )
    )
  )

  (symbol (lib_id "antmicroPushbuttonSwitches:SW_B3U-1000P_SMD") (at 252.73 129.54 270) (unit 1)
    (in_bom yes) (on_board yes) (dnp no) (fields_autoplaced)
    (property "Reference" "PROG_B1" (at 256.54 133.35 90)
      (effects (font (size 1.524 1.524)) (justify left))
    )
    (property "Value" "SW_B3U-1000P" (at 257.175 136.5249 90)
      (effects (font (size 1.27 1.27) (thickness 0.15)) (justify left) hide)
    )
    (property "Footprint" "antmicro-footprints:SW_B3U-1000P_SMD" (at 245.11 154.94 0)
      (effects (font (size 1.27 1.27) (thickness 0.15)) (justify left bottom) hide)
    )
    (property "Datasheet" "https://omronfs.omron.com/en_US/ecb/products/pdf/en-b3u.pdf" (at 242.57 154.94 0)
      (effects (font (size 1.27 1.27) (thickness 0.15)) (justify left bottom) hide)
    )
    (property "MPN" "B3U-1000P" (at 256.54 135.89 90)
      (effects (font (size 1.27 1.27) (thickness 0.15)) (justify left))
    )
    (property "Manufacturer" "Omron" (at 237.49 154.94 0)
      (effects (font (size 1.27 1.27) (thickness 0.15)) (justify left bottom) hide)
    )
    (property "Author" "Antmicro" (at 234.95 154.94 0)
      (effects (font (size 1.27 1.27) (thickness 0.15)) (justify left bottom) hide)
    )
    (property "License" "Apache-2.0" (at 232.41 154.94 0)
      (effects (font (size 1.27 1.27) (thickness 0.15)) (justify left bottom) hide)
    )
    (pin "1")
    (pin "2")
    (instances
      (project "data-center-rdimm-ddr4-tester"
        (path ""
          (reference "PROG_B1") (unit 1)
        )
      )
    )
  )

  (symbol (lib_id "antmicroResistors0402:R_4k7_0402") (at 252.73 108.585 270) (unit 1)
    (in_bom yes) (on_board yes) (dnp no) (fields_autoplaced)
    (property "Reference" "R32" (at 254.635 109.855 90)
      (effects (font (size 1.524 1.524)) (justify left))
    )
    (property "Value" "R_4k7_0402" (at 240.03 128.905 0)
      (effects (font (size 1.27 1.27) (thickness 0.15)) (justify left bottom) hide)
    )
    (property "Footprint" "antmicro-footprints:R_0402_1005Metric" (at 237.49 128.905 0)
      (effects (font (size 1.27 1.27) (thickness 0.15)) (justify left bottom) hide)
    )
    (property "Datasheet" "https://www.bourns.com/docs/product-datasheets/cr.pdf" (at 234.95 128.905 0)
      (effects (font (size 1.27 1.27) (thickness 0.15)) (justify left bottom) hide)
    )
    (property "Manufacturer" "Bourns" (at 229.87 128.905 0)
      (effects (font (size 1.27 1.27) (thickness 0.15)) (justify left bottom) hide)
    )
    (property "MPN" "CR0402-FX-4701GLF" (at 232.41 128.905 0)
      (effects (font (size 1.27 1.27) (thickness 0.15)) (justify left bottom) hide)
    )
    (property "Val" "4k7" (at 254.635 113.0299 90)
      (effects (font (size 1.27 1.27) (thickness 0.15)) (justify left))
    )
    (property "License" "Apache-2.0" (at 227.33 128.905 0)
      (effects (font (size 1.27 1.27) (thickness 0.15)) (justify left bottom) hide)
    )
    (property "Author" "Antmicro" (at 224.79 128.905 0)
      (effects (font (size 1.27 1.27) (thickness 0.15)) (justify left bottom) hide)
    )
    (property "Tolerance" "1%" (at 242.57 128.905 0)
      (effects (font (size 1.27 1.27)) (justify left bottom) hide)
    )
    (pin "1")
    (pin "2")
    (instances
      (project "data-center-rdimm-ddr4-tester"
        (path ""
          (reference "R32") (unit 1)
        )
      )
    )
  )

  (symbol (lib_id "antmicroResistors0402:R_330R_0402") (at 261.62 108.585 270) (unit 1)
    (in_bom yes) (on_board yes) (dnp no) (fields_autoplaced)
    (property "Reference" "R57" (at 263.525 109.855 90)
      (effects (font (size 1.524 1.524)) (justify left))
    )
    (property "Value" "R_330R_0402" (at 248.92 128.905 0)
      (effects (font (size 1.27 1.27) (thickness 0.15)) (justify left bottom) hide)
    )
    (property "Footprint" "antmicro-footprints:R_0402_1005Metric" (at 246.38 128.905 0)
      (effects (font (size 1.27 1.27) (thickness 0.15)) (justify left bottom) hide)
    )
    (property "Datasheet" "https://www.bourns.com/docs/product-datasheets/cr.pdf" (at 243.84 128.905 0)
      (effects (font (size 1.27 1.27) (thickness 0.15)) (justify left bottom) hide)
    )
    (property "Manufacturer" "Bourns" (at 238.76 128.905 0)
      (effects (font (size 1.27 1.27) (thickness 0.15)) (justify left bottom) hide)
    )
    (property "MPN" "CR0402-FX-3300GLF" (at 241.3 128.905 0)
      (effects (font (size 1.27 1.27) (thickness 0.15)) (justify left bottom) hide)
    )
    (property "Val" "330R" (at 263.525 113.0299 90)
      (effects (font (size 1.27 1.27) (thickness 0.15)) (justify left))
    )
    (property "License" "Apache-2.0" (at 236.22 128.905 0)
      (effects (font (size 1.27 1.27) (thickness 0.15)) (justify left bottom) hide)
    )
    (property "Author" "Antmicro" (at 233.68 128.905 0)
      (effects (font (size 1.27 1.27) (thickness 0.15)) (justify left bottom) hide)
    )
    (property "Tolerance" "1%" (at 251.46 128.905 0)
      (effects (font (size 1.27 1.27)) (justify left bottom) hide)
    )
    (pin "1")
    (pin "2")
    (instances
      (project "data-center-rdimm-ddr4-tester"
        (path ""
          (reference "R57") (unit 1)
        )
      )
    )
  )

  (symbol (lib_id "antmicropower:GND") (at 178.435 238.125 90) (unit 1)
    (in_bom yes) (on_board yes) (dnp no) (fields_autoplaced)
    (property "Reference" "#PWR01" (at 184.785 238.125 0)
      (effects (font (size 1.27 1.27)) hide)
    )
    (property "Value" "GND" (at 181.61 238.1249 90)
      (effects (font (size 1.27 1.27)) (justify right))
    )
    (property "Footprint" "" (at 178.435 238.125 0)
      (effects (font (size 1.27 1.27)) hide)
    )
    (property "Datasheet" "" (at 178.435 238.125 0)
      (effects (font (size 1.27 1.27)) hide)
    )
    (property "Author" "Antmicro" (at 186.055 229.235 0)
      (effects (font (size 1.27 1.27) (thickness 0.15)) (justify left bottom) hide)
    )
    (property "License" "Apache-2.0" (at 188.595 229.235 0)
      (effects (font (size 1.27 1.27) (thickness 0.15)) (justify left bottom) hide)
    )
    (pin "1")
    (instances
      (project "data-center-rdimm-ddr4-tester"
        (path ""
          (reference "#PWR01") (unit 1)
        )
      )
    )
  )

  (symbol (lib_id "antmicroResistors0402:R_330R_0402") (at 154.94 238.125 0) (unit 1)
    (in_bom yes) (on_board yes) (dnp no)
    (property "Reference" "R30" (at 157.48 233.68 0)
      (effects (font (size 1.524 1.524)))
    )
    (property "Value" "R_330R_0402" (at 175.26 250.825 0)
      (effects (font (size 1.27 1.27) (thickness 0.15)) (justify left bottom) hide)
    )
    (property "Footprint" "antmicro-footprints:R_0402_1005Metric" (at 175.26 253.365 0)
      (effects (font (size 1.27 1.27) (thickness 0.15)) (justify left bottom) hide)
    )
    (property "Datasheet" "https://www.bourns.com/docs/product-datasheets/cr.pdf" (at 175.26 255.905 0)
      (effects (font (size 1.27 1.27) (thickness 0.15)) (justify left bottom) hide)
    )
    (property "Manufacturer" "Bourns" (at 175.26 260.985 0)
      (effects (font (size 1.27 1.27) (thickness 0.15)) (justify left bottom) hide)
    )
    (property "MPN" "CR0402-FX-3300GLF" (at 175.26 258.445 0)
      (effects (font (size 1.27 1.27) (thickness 0.15)) (justify left bottom) hide)
    )
    (property "Val" "330R" (at 157.48 236.22 0)
      (effects (font (size 1.27 1.27) (thickness 0.15)))
    )
    (property "License" "Apache-2.0" (at 175.26 263.525 0)
      (effects (font (size 1.27 1.27) (thickness 0.15)) (justify left bottom) hide)
    )
    (property "Author" "Antmicro" (at 175.26 266.065 0)
      (effects (font (size 1.27 1.27) (thickness 0.15)) (justify left bottom) hide)
    )
    (property "Tolerance" "1%" (at 175.26 248.285 0)
      (effects (font (size 1.27 1.27)) (justify left bottom) hide)
    )
    (pin "1")
    (pin "2")
    (instances
      (project "data-center-rdimm-ddr4-tester"
        (path ""
          (reference "R30") (unit 1)
        )
      )
    )
  )

  (symbol (lib_id "antmicroLEDIndicationDiscrete:LED_G_0603_KP-1608CGCK") (at 144.145 238.125 0) (unit 1)
    (in_bom yes) (on_board yes) (dnp no)
    (property "Reference" "D1" (at 147.955 231.14 0)
      (effects (font (size 1.524 1.524)))
    )
    (property "Value" "LED_G_0603_KP-1608CGCK" (at 147.955 233.68 0)
      (effects (font (size 1.27 1.27) (thickness 0.15)) hide)
    )
    (property "Footprint" "antmicro-footprints:LED_0603_1608Metric_G" (at 167.005 248.285 0)
      (effects (font (size 1.27 1.27) (thickness 0.15)) (justify left bottom) hide)
    )
    (property "Datasheet" "http://www.farnell.com/datasheets/2045956.pdf" (at 167.005 250.825 0)
      (effects (font (size 1.27 1.27) (thickness 0.15)) (justify left bottom) hide)
    )
    (property "MPN" "KP-1608CGCK" (at 149.86 233.68 0)
      (effects (font (size 1.27 1.27) (thickness 0.15)) (justify right))
    )
    (property "Manufacturer" "Kingbright" (at 167.005 255.905 0)
      (effects (font (size 1.27 1.27) (thickness 0.15)) (justify left bottom) hide)
    )
    (property "Author" "Antmicro" (at 167.005 258.445 0)
      (effects (font (size 1.27 1.27) (thickness 0.15)) (justify left bottom) hide)
    )
    (property "License" "Apache-2.0" (at 167.005 260.985 0)
      (effects (font (size 1.27 1.27) (thickness 0.15)) (justify left bottom) hide)
    )
    (pin "1")
    (pin "2")
    (instances
      (project "data-center-rdimm-ddr4-tester"
        (path ""
          (reference "D1") (unit 1)
        )
      )
    )
  )

  (symbol (lib_id "antmicropower:GND") (at 178.435 257.81 90) (unit 1)
    (in_bom yes) (on_board yes) (dnp no) (fields_autoplaced)
    (property "Reference" "#PWR02" (at 184.785 257.81 0)
      (effects (font (size 1.27 1.27)) hide)
    )
    (property "Value" "GND" (at 182.245 257.8099 90)
      (effects (font (size 1.27 1.27)) (justify right))
    )
    (property "Footprint" "" (at 178.435 257.81 0)
      (effects (font (size 1.27 1.27)) hide)
    )
    (property "Datasheet" "" (at 178.435 257.81 0)
      (effects (font (size 1.27 1.27)) hide)
    )
    (property "Author" "Antmicro" (at 186.055 248.92 0)
      (effects (font (size 1.27 1.27) (thickness 0.15)) (justify left bottom) hide)
    )
    (property "License" "Apache-2.0" (at 188.595 248.92 0)
      (effects (font (size 1.27 1.27) (thickness 0.15)) (justify left bottom) hide)
    )
    (pin "1")
    (instances
      (project "data-center-rdimm-ddr4-tester"
        (path ""
          (reference "#PWR02") (unit 1)
        )
      )
    )
  )

  (symbol (lib_id "antmicroResistors0402:R_330R_0402") (at 154.94 257.81 0) (unit 1)
    (in_bom yes) (on_board yes) (dnp no)
    (property "Reference" "R31" (at 157.48 253.365 0)
      (effects (font (size 1.524 1.524)))
    )
    (property "Value" "R_330R_0402" (at 175.26 270.51 0)
      (effects (font (size 1.27 1.27) (thickness 0.15)) (justify left bottom) hide)
    )
    (property "Footprint" "antmicro-footprints:R_0402_1005Metric" (at 175.26 273.05 0)
      (effects (font (size 1.27 1.27) (thickness 0.15)) (justify left bottom) hide)
    )
    (property "Datasheet" "https://www.bourns.com/docs/product-datasheets/cr.pdf" (at 175.26 275.59 0)
      (effects (font (size 1.27 1.27) (thickness 0.15)) (justify left bottom) hide)
    )
    (property "Manufacturer" "Bourns" (at 175.26 280.67 0)
      (effects (font (size 1.27 1.27) (thickness 0.15)) (justify left bottom) hide)
    )
    (property "MPN" "CR0402-FX-3300GLF" (at 175.26 278.13 0)
      (effects (font (size 1.27 1.27) (thickness 0.15)) (justify left bottom) hide)
    )
    (property "Val" "330R" (at 157.48 255.905 0)
      (effects (font (size 1.27 1.27) (thickness 0.15)))
    )
    (property "License" "Apache-2.0" (at 175.26 283.21 0)
      (effects (font (size 1.27 1.27) (thickness 0.15)) (justify left bottom) hide)
    )
    (property "Author" "Antmicro" (at 175.26 285.75 0)
      (effects (font (size 1.27 1.27) (thickness 0.15)) (justify left bottom) hide)
    )
    (property "Tolerance" "1%" (at 175.26 267.97 0)
      (effects (font (size 1.27 1.27)) (justify left bottom) hide)
    )
    (pin "1")
    (pin "2")
    (instances
      (project "data-center-rdimm-ddr4-tester"
        (path ""
          (reference "R31") (unit 1)
        )
      )
    )
  )

  (symbol (lib_id "antmicroLEDIndicationDiscrete:LED_G_0603_KP-1608CGCK") (at 144.145 257.81 0) (unit 1)
    (in_bom yes) (on_board yes) (dnp no)
    (property "Reference" "D10" (at 147.955 250.825 0)
      (effects (font (size 1.524 1.524)))
    )
    (property "Value" "LED_G_0603_KP-1608CGCK" (at 147.955 252.73 0)
      (effects (font (size 1.27 1.27) (thickness 0.15)) hide)
    )
    (property "Footprint" "antmicro-footprints:LED_0603_1608Metric_G" (at 167.005 267.97 0)
      (effects (font (size 1.27 1.27) (thickness 0.15)) (justify left bottom) hide)
    )
    (property "Datasheet" "http://www.farnell.com/datasheets/2045956.pdf" (at 167.005 270.51 0)
      (effects (font (size 1.27 1.27) (thickness 0.15)) (justify left bottom) hide)
    )
    (property "MPN" "KP-1608CGCK" (at 149.86 253.365 0)
      (effects (font (size 1.27 1.27) (thickness 0.15)) (justify right))
    )
    (property "Manufacturer" "Kingbright" (at 167.005 275.59 0)
      (effects (font (size 1.27 1.27) (thickness 0.15)) (justify left bottom) hide)
    )
    (property "Author" "Antmicro" (at 167.005 278.13 0)
      (effects (font (size 1.27 1.27) (thickness 0.15)) (justify left bottom) hide)
    )
    (property "License" "Apache-2.0" (at 167.005 280.67 0)
      (effects (font (size 1.27 1.27) (thickness 0.15)) (justify left bottom) hide)
    )
    (pin "1")
    (pin "2")
    (instances
      (project "data-center-rdimm-ddr4-tester"
        (path ""
          (reference "D10") (unit 1)
        )
      )
    )
  )

  (symbol (lib_id "antmicroTransistorsFETsMOSFETsSingle:BSS138PW") (at 170.18 245.745 90) (unit 1)
    (in_bom yes) (on_board yes) (dnp no)
    (property "Reference" "Q7" (at 167.64 231.14 90)
      (effects (font (size 1.524 1.524)))
    )
    (property "Value" "BSS138PW" (at 167.64 233.68 90)
      (effects (font (size 1.27 1.27) (thickness 0.15)))
    )
    (property "Footprint" "antmicro-footprints:SC70-3" (at 181.61 222.885 0)
      (effects (font (size 1.27 1.27) (thickness 0.15)) (justify left bottom) hide)
    )
    (property "Datasheet" "https://assets.nexperia.com/documents/data-sheet/BSS138PW.pdf" (at 184.15 222.885 0)
      (effects (font (size 1.27 1.27) (thickness 0.15)) (justify left bottom) hide)
    )
    (property "MPN" "BSS138PW" (at 186.69 222.885 0)
      (effects (font (size 1.27 1.27) (thickness 0.15)) (justify left bottom) hide)
    )
    (property "Manufacturer" "Nexperia" (at 189.23 222.885 0)
      (effects (font (size 1.27 1.27) (thickness 0.15)) (justify left bottom) hide)
    )
    (property "Author" "Antmicro" (at 191.77 222.885 0)
      (effects (font (size 1.27 1.27) (thickness 0.15)) (justify left bottom) hide)
    )
    (property "License" "Apache-2.0" (at 194.31 222.885 0)
      (effects (font (size 1.27 1.27) (thickness 0.15)) (justify left bottom) hide)
    )
    (pin "1")
    (pin "2")
    (pin "3")
    (instances
      (project "data-center-rdimm-ddr4-tester"
        (path ""
          (reference "Q7") (unit 1)
        )
      )
    )
  )

  (symbol (lib_id "antmicroTransistorsFETsMOSFETsSingle:BSS138PW") (at 170.18 265.43 90) (unit 1)
    (in_bom yes) (on_board yes) (dnp no)
    (property "Reference" "Q8" (at 167.64 250.825 90)
      (effects (font (size 1.524 1.524)))
    )
    (property "Value" "BSS138PW" (at 167.64 253.365 90)
      (effects (font (size 1.27 1.27) (thickness 0.15)))
    )
    (property "Footprint" "antmicro-footprints:SC70-3" (at 181.61 242.57 0)
      (effects (font (size 1.27 1.27) (thickness 0.15)) (justify left bottom) hide)
    )
    (property "Datasheet" "https://assets.nexperia.com/documents/data-sheet/BSS138PW.pdf" (at 184.15 242.57 0)
      (effects (font (size 1.27 1.27) (thickness 0.15)) (justify left bottom) hide)
    )
    (property "MPN" "BSS138PW" (at 186.69 242.57 0)
      (effects (font (size 1.27 1.27) (thickness 0.15)) (justify left bottom) hide)
    )
    (property "Manufacturer" "Nexperia" (at 189.23 242.57 0)
      (effects (font (size 1.27 1.27) (thickness 0.15)) (justify left bottom) hide)
    )
    (property "Author" "Antmicro" (at 191.77 242.57 0)
      (effects (font (size 1.27 1.27) (thickness 0.15)) (justify left bottom) hide)
    )
    (property "License" "Apache-2.0" (at 194.31 242.57 0)
      (effects (font (size 1.27 1.27) (thickness 0.15)) (justify left bottom) hide)
    )
    (pin "1")
    (pin "2")
    (pin "3")
    (instances
      (project "data-center-rdimm-ddr4-tester"
        (path ""
          (reference "Q8") (unit 1)
        )
      )
    )
  )

  (symbol (lib_id "antmicropower:GND") (at 252.73 139.7 0) (unit 1)
    (in_bom yes) (on_board yes) (dnp no) (fields_autoplaced)
    (property "Reference" "#PWR0117" (at 252.73 146.05 0)
      (effects (font (size 1.27 1.27)) hide)
    )
    (property "Value" "GND" (at 252.73 144.78 0)
      (effects (font (size 1.27 1.27)))
    )
    (property "Footprint" "" (at 252.73 139.7 0)
      (effects (font (size 1.27 1.27)) hide)
    )
    (property "Datasheet" "" (at 252.73 139.7 0)
      (effects (font (size 1.27 1.27)) hide)
    )
    (property "Author" "Antmicro" (at 261.62 147.32 0)
      (effects (font (size 1.27 1.27) (thickness 0.15)) (justify left bottom) hide)
    )
    (property "License" "Apache-2.0" (at 261.62 149.86 0)
      (effects (font (size 1.27 1.27) (thickness 0.15)) (justify left bottom) hide)
    )
    (pin "1")
    (instances
      (project "data-center-rdimm-ddr4-tester"
        (path ""
          (reference "#PWR0117") (unit 1)
        )
      )
    )
  )

  (symbol (lib_id "antmicroResistors0402:R_0R_0402") (at 327.66 83.185 90) (mirror x) (unit 1)
    (in_bom yes) (on_board yes) (dnp no) (fields_autoplaced)
    (property "Reference" "R58" (at 330.2 84.455 90)
      (effects (font (size 1.524 1.524)) (justify right))
    )
    (property "Value" "R_0R_0402" (at 340.36 103.505 0)
      (effects (font (size 1.27 1.27) (thickness 0.15)) (justify left bottom) hide)
    )
    (property "Footprint" "antmicro-footprints:R_0402_1005Metric" (at 342.9 103.505 0)
      (effects (font (size 1.27 1.27) (thickness 0.15)) (justify left bottom) hide)
    )
    (property "Datasheet" "https://industrial.panasonic.com/cdbs/www-data/pdf/RDA0000/AOA0000C301.pdf" (at 345.44 103.505 0)
      (effects (font (size 1.27 1.27) (thickness 0.15)) (justify left bottom) hide)
    )
    (property "Manufacturer" "Panasonic" (at 350.52 103.505 0)
      (effects (font (size 1.27 1.27) (thickness 0.15)) (justify left bottom) hide)
    )
    (property "MPN" "ERJ2GE0R00X" (at 347.98 103.505 0)
      (effects (font (size 1.27 1.27) (thickness 0.15)) (justify left bottom) hide)
    )
    (property "Val" "0R" (at 330.2 87.6299 90)
      (effects (font (size 1.27 1.27) (thickness 0.15)) (justify right))
    )
    (property "License" "Apache-2.0" (at 353.06 103.505 0)
      (effects (font (size 1.27 1.27) (thickness 0.15)) (justify left bottom) hide)
    )
    (property "Author" "Antmicro" (at 355.6 103.505 0)
      (effects (font (size 1.27 1.27) (thickness 0.15)) (justify left bottom) hide)
    )
    (property "Tolerance" "~" (at 337.82 103.505 0)
      (effects (font (size 1.27 1.27)) (justify left bottom) hide)
    )
    (property "Current" "1A" (at 358.14 103.505 0)
      (effects (font (size 1.27 1.27) (thickness 0.15)) (justify left bottom) hide)
    )
    (pin "1")
    (pin "2")
    (instances
      (project "data-center-rdimm-ddr4-tester"
        (path ""
          (reference "R58") (unit 1)
        )
      )
    )
  )

  (symbol (lib_id "antmicroResistors0402:R_100R_0402") (at 329.184 219.456 270) (unit 1)
    (in_bom yes) (on_board yes) (dnp no) (fields_autoplaced)
    (property "Reference" "R10" (at 331.724 220.726 90)
      (effects (font (size 1.524 1.524)) (justify left))
    )
    (property "Value" "R_100R_0402" (at 316.484 239.776 0)
      (effects (font (size 1.27 1.27) (thickness 0.15)) (justify left bottom) hide)
    )
    (property "Footprint" "antmicro-footprints:R_0402_1005Metric" (at 313.944 239.776 0)
      (effects (font (size 1.27 1.27) (thickness 0.15)) (justify left bottom) hide)
    )
    (property "Datasheet" "https://www.bourns.com/docs/product-datasheets/cr.pdf" (at 311.404 239.776 0)
      (effects (font (size 1.27 1.27) (thickness 0.15)) (justify left bottom) hide)
    )
    (property "Manufacturer" "Bourns" (at 306.324 239.776 0)
      (effects (font (size 1.27 1.27) (thickness 0.15)) (justify left bottom) hide)
    )
    (property "MPN" "CR0402-FX-1000GLF" (at 308.864 239.776 0)
      (effects (font (size 1.27 1.27) (thickness 0.15)) (justify left bottom) hide)
    )
    (property "Val" "100R" (at 331.724 223.9009 90)
      (effects (font (size 1.27 1.27) (thickness 0.15)) (justify left))
    )
    (property "License" "Apache-2.0" (at 303.784 239.776 0)
      (effects (font (size 1.27 1.27) (thickness 0.15)) (justify left bottom) hide)
    )
    (property "Author" "Antmicro" (at 301.244 239.776 0)
      (effects (font (size 1.27 1.27) (thickness 0.15)) (justify left bottom) hide)
    )
    (property "Tolerance" "1%" (at 319.024 239.776 0)
      (effects (font (size 1.27 1.27)) (justify left bottom) hide)
    )
    (pin "1")
    (pin "2")
    (instances
      (project "data-center-rdimm-ddr4-tester"
        (path ""
          (reference "R10") (unit 1)
        )
      )
    )
  )

  (symbol (lib_id "antmicroResistors0402:R_100R_0402") (at 329.184 231.902 270) (unit 1)
    (in_bom no) (on_board yes) (dnp yes)
    (property "Reference" "R36" (at 331.724 233.172 90)
      (effects (font (size 1.524 1.524)) (justify left))
    )
    (property "Value" "R_100R_0402" (at 316.484 252.222 0)
      (effects (font (size 1.27 1.27) (thickness 0.15)) (justify left bottom) hide)
    )
    (property "Footprint" "antmicro-footprints:R_0402_1005Metric" (at 313.944 252.222 0)
      (effects (font (size 1.27 1.27) (thickness 0.15)) (justify left bottom) hide)
    )
    (property "Datasheet" "https://www.bourns.com/docs/product-datasheets/cr.pdf" (at 311.404 252.222 0)
      (effects (font (size 1.27 1.27) (thickness 0.15)) (justify left bottom) hide)
    )
    (property "Manufacturer" "Bourns" (at 306.324 252.222 0)
      (effects (font (size 1.27 1.27) (thickness 0.15)) (justify left bottom) hide)
    )
    (property "MPN" "CR0402-FX-1000GLF" (at 308.864 252.222 0)
      (effects (font (size 1.27 1.27) (thickness 0.15)) (justify left bottom) hide)
    )
    (property "Val" "100R" (at 331.724 236.3469 90)
      (effects (font (size 1.27 1.27) (thickness 0.15)) (justify left))
    )
    (property "License" "Apache-2.0" (at 303.784 252.222 0)
      (effects (font (size 1.27 1.27) (thickness 0.15)) (justify left bottom) hide)
    )
    (property "Author" "Antmicro" (at 301.244 252.222 0)
      (effects (font (size 1.27 1.27) (thickness 0.15)) (justify left bottom) hide)
    )
    (property "Tolerance" "1%" (at 319.024 252.222 0)
      (effects (font (size 1.27 1.27)) (justify left bottom) hide)
    )
    (property "DNP" "DNP" (at 329.184 234.442 0)
      (effects (font (size 1.27 1.27)))
    )
    (pin "1")
    (pin "2")
    (instances
      (project "data-center-rdimm-ddr4-tester"
        (path ""
          (reference "R36") (unit 1)
        )
      )
    )
  )

  (symbol (lib_id "antmicropower:GND") (at 329.184 236.982 0) (unit 1)
    (in_bom yes) (on_board yes) (dnp no) (fields_autoplaced)
    (property "Reference" "#PWR03" (at 329.184 243.332 0)
      (effects (font (size 1.27 1.27)) hide)
    )
    (property "Value" "GND" (at 329.184 241.427 0)
      (effects (font (size 1.27 1.27)))
    )
    (property "Footprint" "" (at 329.184 236.982 0)
      (effects (font (size 1.27 1.27)) hide)
    )
    (property "Datasheet" "" (at 329.184 236.982 0)
      (effects (font (size 1.27 1.27)) hide)
    )
    (property "Author" "Antmicro" (at 338.074 244.602 0)
      (effects (font (size 1.27 1.27) (thickness 0.15)) (justify left bottom) hide)
    )
    (property "License" "Apache-2.0" (at 338.074 247.142 0)
      (effects (font (size 1.27 1.27) (thickness 0.15)) (justify left bottom) hide)
    )
    (pin "1")
    (instances
      (project "data-center-rdimm-ddr4-tester"
        (path ""
          (reference "#PWR03") (unit 1)
        )
      )
    )
  )

  (symbol (lib_id "antmicroResistors0402:R_0R_0402") (at 99.695 110.49 0) (unit 1)
    (in_bom yes) (on_board yes) (dnp no)
    (property "Reference" "R26" (at 97.79 109.22 0)
      (effects (font (size 1.524 1.524)))
    )
    (property "Value" "R_0R_0402" (at 120.015 123.19 0)
      (effects (font (size 1.27 1.27) (thickness 0.15)) (justify left bottom) hide)
    )
    (property "Footprint" "antmicro-footprints:R_0402_1005Metric" (at 120.015 125.73 0)
      (effects (font (size 1.27 1.27) (thickness 0.15)) (justify left bottom) hide)
    )
    (property "Datasheet" "https://industrial.panasonic.com/cdbs/www-data/pdf/RDA0000/AOA0000C301.pdf" (at 120.015 128.27 0)
      (effects (font (size 1.27 1.27) (thickness 0.15)) (justify left bottom) hide)
    )
    (property "Manufacturer" "Panasonic" (at 120.015 133.35 0)
      (effects (font (size 1.27 1.27) (thickness 0.15)) (justify left bottom) hide)
    )
    (property "MPN" "ERJ2GE0R00X" (at 120.015 130.81 0)
      (effects (font (size 1.27 1.27) (thickness 0.15)) (justify left bottom) hide)
    )
    (property "Val" "0R" (at 106.045 109.22 0)
      (effects (font (size 1.27 1.27) (thickness 0.15)))
    )
    (property "License" "Apache-2.0" (at 120.015 135.89 0)
      (effects (font (size 1.27 1.27) (thickness 0.15)) (justify left bottom) hide)
    )
    (property "Author" "Antmicro" (at 120.015 138.43 0)
      (effects (font (size 1.27 1.27) (thickness 0.15)) (justify left bottom) hide)
    )
    (property "Tolerance" "~" (at 120.015 120.65 0)
      (effects (font (size 1.27 1.27)) (justify left bottom) hide)
    )
    (property "Current" "1A" (at 120.015 140.97 0)
      (effects (font (size 1.27 1.27) (thickness 0.15)) (justify left bottom) hide)
    )
    (pin "1")
    (pin "2")
    (instances
      (project "data-center-rdimm-ddr4-tester"
        (path ""
          (reference "R26") (unit 1)
        )
      )
    )
  )

  (symbol (lib_id "antmicroResistors0402:R_0R_0402") (at 99.695 107.95 0) (unit 1)
    (in_bom yes) (on_board yes) (dnp no)
    (property "Reference" "R27" (at 97.79 106.68 0)
      (effects (font (size 1.524 1.524)))
    )
    (property "Value" "R_0R_0402" (at 120.015 120.65 0)
      (effects (font (size 1.27 1.27) (thickness 0.15)) (justify left bottom) hide)
    )
    (property "Footprint" "antmicro-footprints:R_0402_1005Metric" (at 120.015 123.19 0)
      (effects (font (size 1.27 1.27) (thickness 0.15)) (justify left bottom) hide)
    )
    (property "Datasheet" "https://industrial.panasonic.com/cdbs/www-data/pdf/RDA0000/AOA0000C301.pdf" (at 120.015 125.73 0)
      (effects (font (size 1.27 1.27) (thickness 0.15)) (justify left bottom) hide)
    )
    (property "Manufacturer" "Panasonic" (at 120.015 130.81 0)
      (effects (font (size 1.27 1.27) (thickness 0.15)) (justify left bottom) hide)
    )
    (property "MPN" "ERJ2GE0R00X" (at 120.015 128.27 0)
      (effects (font (size 1.27 1.27) (thickness 0.15)) (justify left bottom) hide)
    )
    (property "Val" "0R" (at 106.045 106.68 0)
      (effects (font (size 1.27 1.27) (thickness 0.15)))
    )
    (property "License" "Apache-2.0" (at 120.015 133.35 0)
      (effects (font (size 1.27 1.27) (thickness 0.15)) (justify left bottom) hide)
    )
    (property "Author" "Antmicro" (at 120.015 135.89 0)
      (effects (font (size 1.27 1.27) (thickness 0.15)) (justify left bottom) hide)
    )
    (property "Tolerance" "~" (at 120.015 118.11 0)
      (effects (font (size 1.27 1.27)) (justify left bottom) hide)
    )
    (property "Current" "1A" (at 120.015 138.43 0)
      (effects (font (size 1.27 1.27) (thickness 0.15)) (justify left bottom) hide)
    )
    (pin "1")
    (pin "2")
    (instances
      (project "data-center-rdimm-ddr4-tester"
        (path ""
          (reference "R27") (unit 1)
        )
      )
    )
  )

  (symbol (lib_id "antmicroResistors0402:R_0R_0402") (at 99.695 102.87 0) (unit 1)
    (in_bom yes) (on_board yes) (dnp no)
    (property "Reference" "R59" (at 97.79 101.6 0)
      (effects (font (size 1.524 1.524)))
    )
    (property "Value" "R_0R_0402" (at 120.015 115.57 0)
      (effects (font (size 1.27 1.27) (thickness 0.15)) (justify left bottom) hide)
    )
    (property "Footprint" "antmicro-footprints:R_0402_1005Metric" (at 120.015 118.11 0)
      (effects (font (size 1.27 1.27) (thickness 0.15)) (justify left bottom) hide)
    )
    (property "Datasheet" "https://industrial.panasonic.com/cdbs/www-data/pdf/RDA0000/AOA0000C301.pdf" (at 120.015 120.65 0)
      (effects (font (size 1.27 1.27) (thickness 0.15)) (justify left bottom) hide)
    )
    (property "Manufacturer" "Panasonic" (at 120.015 125.73 0)
      (effects (font (size 1.27 1.27) (thickness 0.15)) (justify left bottom) hide)
    )
    (property "MPN" "ERJ2GE0R00X" (at 120.015 123.19 0)
      (effects (font (size 1.27 1.27) (thickness 0.15)) (justify left bottom) hide)
    )
    (property "Val" "0R" (at 106.045 101.6 0)
      (effects (font (size 1.27 1.27) (thickness 0.15)))
    )
    (property "License" "Apache-2.0" (at 120.015 128.27 0)
      (effects (font (size 1.27 1.27) (thickness 0.15)) (justify left bottom) hide)
    )
    (property "Author" "Antmicro" (at 120.015 130.81 0)
      (effects (font (size 1.27 1.27) (thickness 0.15)) (justify left bottom) hide)
    )
    (property "Tolerance" "~" (at 120.015 113.03 0)
      (effects (font (size 1.27 1.27)) (justify left bottom) hide)
    )
    (property "Current" "1A" (at 120.015 133.35 0)
      (effects (font (size 1.27 1.27) (thickness 0.15)) (justify left bottom) hide)
    )
    (pin "1")
    (pin "2")
    (instances
      (project "data-center-rdimm-ddr4-tester"
        (path ""
          (reference "R59") (unit 1)
        )
      )
    )
  )

  (symbol (lib_id "antmicroResistors0402:R_0R_0402") (at 99.695 105.41 0) (unit 1)
    (in_bom yes) (on_board yes) (dnp no)
    (property "Reference" "R60" (at 97.79 104.14 0)
      (effects (font (size 1.524 1.524)))
    )
    (property "Value" "R_0R_0402" (at 120.015 118.11 0)
      (effects (font (size 1.27 1.27) (thickness 0.15)) (justify left bottom) hide)
    )
    (property "Footprint" "antmicro-footprints:R_0402_1005Metric" (at 120.015 120.65 0)
      (effects (font (size 1.27 1.27) (thickness 0.15)) (justify left bottom) hide)
    )
    (property "Datasheet" "https://industrial.panasonic.com/cdbs/www-data/pdf/RDA0000/AOA0000C301.pdf" (at 120.015 123.19 0)
      (effects (font (size 1.27 1.27) (thickness 0.15)) (justify left bottom) hide)
    )
    (property "Manufacturer" "Panasonic" (at 120.015 128.27 0)
      (effects (font (size 1.27 1.27) (thickness 0.15)) (justify left bottom) hide)
    )
    (property "MPN" "ERJ2GE0R00X" (at 120.015 125.73 0)
      (effects (font (size 1.27 1.27) (thickness 0.15)) (justify left bottom) hide)
    )
    (property "Val" "0R" (at 106.045 104.14 0)
      (effects (font (size 1.27 1.27) (thickness 0.15)))
    )
    (property "License" "Apache-2.0" (at 120.015 130.81 0)
      (effects (font (size 1.27 1.27) (thickness 0.15)) (justify left bottom) hide)
    )
    (property "Author" "Antmicro" (at 120.015 133.35 0)
      (effects (font (size 1.27 1.27) (thickness 0.15)) (justify left bottom) hide)
    )
    (property "Tolerance" "~" (at 120.015 115.57 0)
      (effects (font (size 1.27 1.27)) (justify left bottom) hide)
    )
    (property "Current" "1A" (at 120.015 135.89 0)
      (effects (font (size 1.27 1.27) (thickness 0.15)) (justify left bottom) hide)
    )
    (pin "1")
    (pin "2")
    (instances
      (project "data-center-rdimm-ddr4-tester"
        (path ""
          (reference "R60") (unit 1)
        )
      )
    )
  )

  (symbol (lib_id "antmicroResistors0402:R_0R_0402") (at 99.695 113.03 0) (unit 1)
    (in_bom yes) (on_board yes) (dnp no)
    (property "Reference" "R24" (at 97.79 111.76 0)
      (effects (font (size 1.524 1.524)))
    )
    (property "Value" "R_0R_0402" (at 120.015 125.73 0)
      (effects (font (size 1.27 1.27) (thickness 0.15)) (justify left bottom) hide)
    )
    (property "Footprint" "antmicro-footprints:R_0402_1005Metric" (at 120.015 128.27 0)
      (effects (font (size 1.27 1.27) (thickness 0.15)) (justify left bottom) hide)
    )
    (property "Datasheet" "https://industrial.panasonic.com/cdbs/www-data/pdf/RDA0000/AOA0000C301.pdf" (at 120.015 130.81 0)
      (effects (font (size 1.27 1.27) (thickness 0.15)) (justify left bottom) hide)
    )
    (property "Manufacturer" "Panasonic" (at 120.015 135.89 0)
      (effects (font (size 1.27 1.27) (thickness 0.15)) (justify left bottom) hide)
    )
    (property "MPN" "ERJ2GE0R00X" (at 120.015 133.35 0)
      (effects (font (size 1.27 1.27) (thickness 0.15)) (justify left bottom) hide)
    )
    (property "Val" "0R" (at 106.045 111.76 0)
      (effects (font (size 1.27 1.27) (thickness 0.15)))
    )
    (property "License" "Apache-2.0" (at 120.015 138.43 0)
      (effects (font (size 1.27 1.27) (thickness 0.15)) (justify left bottom) hide)
    )
    (property "Author" "Antmicro" (at 120.015 140.97 0)
      (effects (font (size 1.27 1.27) (thickness 0.15)) (justify left bottom) hide)
    )
    (property "Tolerance" "~" (at 120.015 123.19 0)
      (effects (font (size 1.27 1.27)) (justify left bottom) hide)
    )
    (property "Current" "1A" (at 120.015 143.51 0)
      (effects (font (size 1.27 1.27) (thickness 0.15)) (justify left bottom) hide)
    )
    (pin "1")
    (pin "2")
    (instances
      (project "data-center-rdimm-ddr4-tester"
        (path ""
          (reference "R24") (unit 1)
        )
      )
    )
  )

  (symbol (lib_id "antmicroResistors0402:R_0R_0402") (at 99.695 115.57 0) (unit 1)
    (in_bom yes) (on_board yes) (dnp no)
    (property "Reference" "R23" (at 97.79 114.3 0)
      (effects (font (size 1.524 1.524)))
    )
    (property "Value" "R_0R_0402" (at 120.015 128.27 0)
      (effects (font (size 1.27 1.27) (thickness 0.15)) (justify left bottom) hide)
    )
    (property "Footprint" "antmicro-footprints:R_0402_1005Metric" (at 120.015 130.81 0)
      (effects (font (size 1.27 1.27) (thickness 0.15)) (justify left bottom) hide)
    )
    (property "Datasheet" "https://industrial.panasonic.com/cdbs/www-data/pdf/RDA0000/AOA0000C301.pdf" (at 120.015 133.35 0)
      (effects (font (size 1.27 1.27) (thickness 0.15)) (justify left bottom) hide)
    )
    (property "Manufacturer" "Panasonic" (at 120.015 138.43 0)
      (effects (font (size 1.27 1.27) (thickness 0.15)) (justify left bottom) hide)
    )
    (property "MPN" "ERJ2GE0R00X" (at 120.015 135.89 0)
      (effects (font (size 1.27 1.27) (thickness 0.15)) (justify left bottom) hide)
    )
    (property "Val" "0R" (at 106.045 114.3 0)
      (effects (font (size 1.27 1.27) (thickness 0.15)))
    )
    (property "License" "Apache-2.0" (at 120.015 140.97 0)
      (effects (font (size 1.27 1.27) (thickness 0.15)) (justify left bottom) hide)
    )
    (property "Author" "Antmicro" (at 120.015 143.51 0)
      (effects (font (size 1.27 1.27) (thickness 0.15)) (justify left bottom) hide)
    )
    (property "Tolerance" "~" (at 120.015 125.73 0)
      (effects (font (size 1.27 1.27)) (justify left bottom) hide)
    )
    (property "Current" "1A" (at 120.015 146.05 0)
      (effects (font (size 1.27 1.27) (thickness 0.15)) (justify left bottom) hide)
    )
    (pin "1")
    (pin "2")
    (instances
      (project "data-center-rdimm-ddr4-tester"
        (path ""
          (reference "R23") (unit 1)
        )
      )
    )
  )

  (symbol (lib_id "antmicroResistors0402:R_4k7_0402") (at 128.905 92.075 90) (mirror x) (unit 1)
    (in_bom yes) (on_board yes) (dnp no) (fields_autoplaced)
    (property "Reference" "R21" (at 130.81 93.345 90)
      (effects (font (size 1.524 1.524)) (justify right))
    )
    (property "Value" "R_4k7_0402" (at 141.605 112.395 0)
      (effects (font (size 1.27 1.27) (thickness 0.15)) (justify left bottom) hide)
    )
    (property "Footprint" "antmicro-footprints:R_0402_1005Metric" (at 144.145 112.395 0)
      (effects (font (size 1.27 1.27) (thickness 0.15)) (justify left bottom) hide)
    )
    (property "Datasheet" "https://www.bourns.com/docs/product-datasheets/cr.pdf" (at 146.685 112.395 0)
      (effects (font (size 1.27 1.27) (thickness 0.15)) (justify left bottom) hide)
    )
    (property "Manufacturer" "Bourns" (at 151.765 112.395 0)
      (effects (font (size 1.27 1.27) (thickness 0.15)) (justify left bottom) hide)
    )
    (property "MPN" "CR0402-FX-4701GLF" (at 149.225 112.395 0)
      (effects (font (size 1.27 1.27) (thickness 0.15)) (justify left bottom) hide)
    )
    (property "Val" "4k7" (at 130.81 96.5199 90)
      (effects (font (size 1.27 1.27) (thickness 0.15)) (justify right))
    )
    (property "License" "Apache-2.0" (at 154.305 112.395 0)
      (effects (font (size 1.27 1.27) (thickness 0.15)) (justify left bottom) hide)
    )
    (property "Author" "Antmicro" (at 156.845 112.395 0)
      (effects (font (size 1.27 1.27) (thickness 0.15)) (justify left bottom) hide)
    )
    (property "Tolerance" "1%" (at 139.065 112.395 0)
      (effects (font (size 1.27 1.27)) (justify left bottom) hide)
    )
    (pin "1")
    (pin "2")
    (instances
      (project "data-center-rdimm-ddr4-tester"
        (path ""
          (reference "R21") (unit 1)
        )
      )
    )
  )

  (symbol (lib_id "antmicroResistors0402:R_4k7_0402") (at 137.16 92.075 90) (mirror x) (unit 1)
    (in_bom yes) (on_board yes) (dnp no)
    (property "Reference" "R22" (at 139.065 93.3451 90)
      (effects (font (size 1.524 1.524)) (justify right))
    )
    (property "Value" "R_4k7_0402" (at 149.86 112.395 0)
      (effects (font (size 1.27 1.27) (thickness 0.15)) (justify left bottom) hide)
    )
    (property "Footprint" "antmicro-footprints:R_0402_1005Metric" (at 152.4 112.395 0)
      (effects (font (size 1.27 1.27) (thickness 0.15)) (justify left bottom) hide)
    )
    (property "Datasheet" "https://www.bourns.com/docs/product-datasheets/cr.pdf" (at 154.94 112.395 0)
      (effects (font (size 1.27 1.27) (thickness 0.15)) (justify left bottom) hide)
    )
    (property "Manufacturer" "Bourns" (at 160.02 112.395 0)
      (effects (font (size 1.27 1.27) (thickness 0.15)) (justify left bottom) hide)
    )
    (property "MPN" "CR0402-FX-4701GLF" (at 157.48 112.395 0)
      (effects (font (size 1.27 1.27) (thickness 0.15)) (justify left bottom) hide)
    )
    (property "Val" "4k7" (at 139.065 96.52 90)
      (effects (font (size 1.27 1.27) (thickness 0.15)) (justify right))
    )
    (property "License" "Apache-2.0" (at 162.56 112.395 0)
      (effects (font (size 1.27 1.27) (thickness 0.15)) (justify left bottom) hide)
    )
    (property "Author" "Antmicro" (at 165.1 112.395 0)
      (effects (font (size 1.27 1.27) (thickness 0.15)) (justify left bottom) hide)
    )
    (property "Tolerance" "1%" (at 147.32 112.395 0)
      (effects (font (size 1.27 1.27)) (justify left bottom) hide)
    )
    (pin "1")
    (pin "2")
    (instances
      (project "data-center-rdimm-ddr4-tester"
        (path ""
          (reference "R22") (unit 1)
        )
      )
    )
  )

  (symbol (lib_id "antmicroResistors0402:R_100R_0402") (at 120.015 92.075 270) (unit 1)
    (in_bom no) (on_board yes) (dnp yes)
    (property "Reference" "R33" (at 121.92 93.345 90)
      (effects (font (size 1.524 1.524)) (justify left))
    )
    (property "Value" "R_100R_0402" (at 107.315 112.395 0)
      (effects (font (size 1.27 1.27) (thickness 0.15)) (justify left bottom) hide)
    )
    (property "Footprint" "antmicro-footprints:R_0402_1005Metric" (at 104.775 112.395 0)
      (effects (font (size 1.27 1.27) (thickness 0.15)) (justify left bottom) hide)
    )
    (property "Datasheet" "https://www.bourns.com/docs/product-datasheets/cr.pdf" (at 102.235 112.395 0)
      (effects (font (size 1.27 1.27) (thickness 0.15)) (justify left bottom) hide)
    )
    (property "Manufacturer" "Bourns" (at 97.155 112.395 0)
      (effects (font (size 1.27 1.27) (thickness 0.15)) (justify left bottom) hide)
    )
    (property "MPN" "CR0402-FX-1000GLF" (at 99.695 112.395 0)
      (effects (font (size 1.27 1.27) (thickness 0.15)) (justify left bottom) hide)
    )
    (property "Val" "100R" (at 121.92 96.5199 90)
      (effects (font (size 1.27 1.27) (thickness 0.15)) (justify left))
    )
    (property "License" "Apache-2.0" (at 94.615 112.395 0)
      (effects (font (size 1.27 1.27) (thickness 0.15)) (justify left bottom) hide)
    )
    (property "Author" "Antmicro" (at 92.075 112.395 0)
      (effects (font (size 1.27 1.27) (thickness 0.15)) (justify left bottom) hide)
    )
    (property "Tolerance" "1%" (at 109.855 112.395 0)
      (effects (font (size 1.27 1.27)) (justify left bottom) hide)
    )
    (property "DNP" "DNP" (at 120.015 94.615 0)
      (effects (font (size 1.27 1.27)))
    )
    (pin "1")
    (pin "2")
    (instances
      (project "data-center-rdimm-ddr4-tester"
        (path ""
          (reference "R33") (unit 1)
        )
      )
    )
  )

  (symbol (lib_id "antmicroResistors0402:R_0R_0402") (at 230.505 230.505 0) (unit 1)
    (in_bom yes) (on_board yes) (dnp no)
    (property "Reference" "R9" (at 228.6 229.235 0)
      (effects (font (size 1.524 1.524)))
    )
    (property "Value" "R_0R_0402" (at 250.825 243.205 0)
      (effects (font (size 1.27 1.27) (thickness 0.15)) (justify left bottom) hide)
    )
    (property "Footprint" "antmicro-footprints:R_0402_1005Metric" (at 250.825 245.745 0)
      (effects (font (size 1.27 1.27) (thickness 0.15)) (justify left bottom) hide)
    )
    (property "Datasheet" "https://industrial.panasonic.com/cdbs/www-data/pdf/RDA0000/AOA0000C301.pdf" (at 250.825 248.285 0)
      (effects (font (size 1.27 1.27) (thickness 0.15)) (justify left bottom) hide)
    )
    (property "Manufacturer" "Panasonic" (at 250.825 253.365 0)
      (effects (font (size 1.27 1.27) (thickness 0.15)) (justify left bottom) hide)
    )
    (property "MPN" "ERJ2GE0R00X" (at 250.825 250.825 0)
      (effects (font (size 1.27 1.27) (thickness 0.15)) (justify left bottom) hide)
    )
    (property "Val" "0R" (at 236.855 229.235 0)
      (effects (font (size 1.27 1.27) (thickness 0.15)))
    )
    (property "License" "Apache-2.0" (at 250.825 255.905 0)
      (effects (font (size 1.27 1.27) (thickness 0.15)) (justify left bottom) hide)
    )
    (property "Author" "Antmicro" (at 250.825 258.445 0)
      (effects (font (size 1.27 1.27) (thickness 0.15)) (justify left bottom) hide)
    )
    (property "Tolerance" "~" (at 250.825 240.665 0)
      (effects (font (size 1.27 1.27)) (justify left bottom) hide)
    )
    (property "Current" "1A" (at 250.825 260.985 0)
      (effects (font (size 1.27 1.27) (thickness 0.15)) (justify left bottom) hide)
    )
    (pin "1")
    (pin "2")
    (instances
      (project "data-center-rdimm-ddr4-tester"
        (path ""
          (reference "R9") (unit 1)
        )
      )
    )
  )

  (symbol (lib_id "antmicroResistors0402:R_0R_0402") (at 230.505 235.585 0) (unit 1)
    (in_bom no) (on_board yes) (dnp yes)
    (property "Reference" "R11" (at 228.6 234.315 0)
      (effects (font (size 1.524 1.524)))
    )
    (property "Value" "R_0R_0402" (at 250.825 248.285 0)
      (effects (font (size 1.27 1.27) (thickness 0.15)) (justify left bottom) hide)
    )
    (property "Footprint" "antmicro-footprints:R_0402_1005Metric" (at 250.825 250.825 0)
      (effects (font (size 1.27 1.27) (thickness 0.15)) (justify left bottom) hide)
    )
    (property "Datasheet" "https://industrial.panasonic.com/cdbs/www-data/pdf/RDA0000/AOA0000C301.pdf" (at 250.825 253.365 0)
      (effects (font (size 1.27 1.27) (thickness 0.15)) (justify left bottom) hide)
    )
    (property "Manufacturer" "Panasonic" (at 250.825 258.445 0)
      (effects (font (size 1.27 1.27) (thickness 0.15)) (justify left bottom) hide)
    )
    (property "MPN" "ERJ2GE0R00X" (at 250.825 255.905 0)
      (effects (font (size 1.27 1.27) (thickness 0.15)) (justify left bottom) hide)
    )
    (property "Val" "0R" (at 236.855 234.315 0)
      (effects (font (size 1.27 1.27) (thickness 0.15)))
    )
    (property "License" "Apache-2.0" (at 250.825 260.985 0)
      (effects (font (size 1.27 1.27) (thickness 0.15)) (justify left bottom) hide)
    )
    (property "Author" "Antmicro" (at 250.825 263.525 0)
      (effects (font (size 1.27 1.27) (thickness 0.15)) (justify left bottom) hide)
    )
    (property "Tolerance" "~" (at 250.825 245.745 0)
      (effects (font (size 1.27 1.27)) (justify left bottom) hide)
    )
    (property "Current" "1A" (at 250.825 266.065 0)
      (effects (font (size 1.27 1.27) (thickness 0.15)) (justify left bottom) hide)
    )
    (property "DNP" "DNP" (at 233.045 235.585 0)
      (effects (font (size 1.27 1.27)))
    )
    (pin "1")
    (pin "2")
    (instances
      (project "data-center-rdimm-ddr4-tester"
        (path ""
          (reference "R11") (unit 1)
        )
      )
    )
  )

  (symbol (lib_id "antmicroResistors0402:R_0R_0402") (at 230.505 243.205 0) (unit 1)
    (in_bom no) (on_board yes) (dnp yes)
    (property "Reference" "R12" (at 228.6 241.935 0)
      (effects (font (size 1.524 1.524)))
    )
    (property "Value" "R_0R_0402" (at 250.825 255.905 0)
      (effects (font (size 1.27 1.27) (thickness 0.15)) (justify left bottom) hide)
    )
    (property "Footprint" "antmicro-footprints:R_0402_1005Metric" (at 250.825 258.445 0)
      (effects (font (size 1.27 1.27) (thickness 0.15)) (justify left bottom) hide)
    )
    (property "Datasheet" "https://industrial.panasonic.com/cdbs/www-data/pdf/RDA0000/AOA0000C301.pdf" (at 250.825 260.985 0)
      (effects (font (size 1.27 1.27) (thickness 0.15)) (justify left bottom) hide)
    )
    (property "Manufacturer" "Panasonic" (at 250.825 266.065 0)
      (effects (font (size 1.27 1.27) (thickness 0.15)) (justify left bottom) hide)
    )
    (property "MPN" "ERJ2GE0R00X" (at 250.825 263.525 0)
      (effects (font (size 1.27 1.27) (thickness 0.15)) (justify left bottom) hide)
    )
    (property "Val" "0R" (at 236.855 241.935 0)
      (effects (font (size 1.27 1.27) (thickness 0.15)))
    )
    (property "License" "Apache-2.0" (at 250.825 268.605 0)
      (effects (font (size 1.27 1.27) (thickness 0.15)) (justify left bottom) hide)
    )
    (property "Author" "Antmicro" (at 250.825 271.145 0)
      (effects (font (size 1.27 1.27) (thickness 0.15)) (justify left bottom) hide)
    )
    (property "Tolerance" "~" (at 250.825 253.365 0)
      (effects (font (size 1.27 1.27)) (justify left bottom) hide)
    )
    (property "Current" "1A" (at 250.825 273.685 0)
      (effects (font (size 1.27 1.27) (thickness 0.15)) (justify left bottom) hide)
    )
    (property "DNP" "DNP" (at 233.045 243.205 0)
      (effects (font (size 1.27 1.27)))
    )
    (pin "1")
    (pin "2")
    (instances
      (project "data-center-rdimm-ddr4-tester"
        (path ""
          (reference "R12") (unit 1)
        )
      )
    )
  )

  (symbol (lib_id "antmicroResistors0402:R_0R_0402") (at 230.505 248.285 0) (unit 1)
    (in_bom yes) (on_board yes) (dnp no)
    (property "Reference" "R13" (at 228.6 247.015 0)
      (effects (font (size 1.524 1.524)))
    )
    (property "Value" "R_0R_0402" (at 250.825 260.985 0)
      (effects (font (size 1.27 1.27) (thickness 0.15)) (justify left bottom) hide)
    )
    (property "Footprint" "antmicro-footprints:R_0402_1005Metric" (at 250.825 263.525 0)
      (effects (font (size 1.27 1.27) (thickness 0.15)) (justify left bottom) hide)
    )
    (property "Datasheet" "https://industrial.panasonic.com/cdbs/www-data/pdf/RDA0000/AOA0000C301.pdf" (at 250.825 266.065 0)
      (effects (font (size 1.27 1.27) (thickness 0.15)) (justify left bottom) hide)
    )
    (property "Manufacturer" "Panasonic" (at 250.825 271.145 0)
      (effects (font (size 1.27 1.27) (thickness 0.15)) (justify left bottom) hide)
    )
    (property "MPN" "ERJ2GE0R00X" (at 250.825 268.605 0)
      (effects (font (size 1.27 1.27) (thickness 0.15)) (justify left bottom) hide)
    )
    (property "Val" "0R" (at 236.855 247.015 0)
      (effects (font (size 1.27 1.27) (thickness 0.15)))
    )
    (property "License" "Apache-2.0" (at 250.825 273.685 0)
      (effects (font (size 1.27 1.27) (thickness 0.15)) (justify left bottom) hide)
    )
    (property "Author" "Antmicro" (at 250.825 276.225 0)
      (effects (font (size 1.27 1.27) (thickness 0.15)) (justify left bottom) hide)
    )
    (property "Tolerance" "~" (at 250.825 258.445 0)
      (effects (font (size 1.27 1.27)) (justify left bottom) hide)
    )
    (property "Current" "1A" (at 250.825 278.765 0)
      (effects (font (size 1.27 1.27) (thickness 0.15)) (justify left bottom) hide)
    )
    (pin "1")
    (pin "2")
    (instances
      (project "data-center-rdimm-ddr4-tester"
        (path ""
          (reference "R13") (unit 1)
        )
      )
    )
  )

  (symbol (lib_id "antmicropower:GND") (at 247.65 266.065 0) (unit 1)
    (in_bom yes) (on_board yes) (dnp no) (fields_autoplaced)
    (property "Reference" "#PWR04" (at 247.65 272.415 0)
      (effects (font (size 1.27 1.27)) hide)
    )
    (property "Value" "GND" (at 247.65 270.51 0)
      (effects (font (size 1.27 1.27)))
    )
    (property "Footprint" "" (at 247.65 266.065 0)
      (effects (font (size 1.27 1.27)) hide)
    )
    (property "Datasheet" "" (at 247.65 266.065 0)
      (effects (font (size 1.27 1.27)) hide)
    )
    (property "Author" "Antmicro" (at 256.54 273.685 0)
      (effects (font (size 1.27 1.27) (thickness 0.15)) (justify left bottom) hide)
    )
    (property "License" "Apache-2.0" (at 256.54 276.225 0)
      (effects (font (size 1.27 1.27) (thickness 0.15)) (justify left bottom) hide)
    )
    (pin "1")
    (instances
      (project "data-center-rdimm-ddr4-tester"
        (path ""
          (reference "#PWR04") (unit 1)
        )
      )
    )
  )

  (symbol (lib_id "antmicroCapacitors0402:C_470n_0402") (at 378.46 94.615 270) (unit 1)
    (in_bom yes) (on_board yes) (dnp no)
    (property "Reference" "C37" (at 379.095 95.25 90)
      (effects (font (size 1.524 1.524)) (justify left))
    )
    (property "Value" "C_470n_0402" (at 368.3 114.935 0)
      (effects (font (size 1.27 1.27) (thickness 0.15)) (justify left bottom) hide)
    )
    (property "Footprint" "antmicro-footprints:C_0402_1005Metric" (at 365.76 114.935 0)
      (effects (font (size 1.27 1.27) (thickness 0.15)) (justify left bottom) hide)
    )
    (property "Datasheet" " " (at 363.22 114.935 0)
      (effects (font (size 1.27 1.27) (thickness 0.15)) (justify left bottom) hide)
    )
    (property "Manufacturer" "TDK" (at 358.14 114.935 0)
      (effects (font (size 1.27 1.27) (thickness 0.15)) (justify left bottom) hide)
    )
    (property "MPN" "C1005X5R1E474M050BB" (at 360.68 114.935 0)
      (effects (font (size 1.27 1.27) (thickness 0.15)) (justify left bottom) hide)
    )
    (property "Val" "470n" (at 379.095 99.06 90)
      (effects (font (size 1.27 1.27) (thickness 0.15)) (justify left))
    )
    (property "License" "Apache-2.0" (at 355.6 114.935 0)
      (effects (font (size 1.27 1.27) (thickness 0.15)) (justify left bottom) hide)
    )
    (property "Author" "Antmicro" (at 353.06 114.935 0)
      (effects (font (size 1.27 1.27) (thickness 0.15)) (justify left bottom) hide)
    )
    (property "Voltage" "" (at 350.52 114.935 0)
      (effects (font (size 1.27 1.27)) (justify left bottom) hide)
    )
    (property "Dielectric" "" (at 347.98 114.935 0)
      (effects (font (size 1.27 1.27)) (justify left bottom) hide)
    )
    (pin "1")
    (pin "2")
    (instances
      (project "data-center-rdimm-ddr4-tester"
        (path ""
          (reference "C37") (unit 1)
        )
      )
    )
  )

  (symbol (lib_id "antmicroResistors0402:R_2k2_0402") (at 111.125 92.075 270) (unit 1)
    (in_bom yes) (on_board yes) (dnp no) (fields_autoplaced)
    (property "Reference" "R14" (at 113.03 93.345 90)
      (effects (font (size 1.524 1.524)) (justify left))
    )
    (property "Value" "R_2k2_0402" (at 98.425 112.395 0)
      (effects (font (size 1.27 1.27) (thickness 0.15)) (justify left bottom) hide)
    )
    (property "Footprint" "antmicro-footprints:R_0402_1005Metric" (at 95.885 112.395 0)
      (effects (font (size 1.27 1.27) (thickness 0.15)) (justify left bottom) hide)
    )
    (property "Datasheet" "https://www.bourns.com/docs/product-datasheets/cr.pdf" (at 93.345 112.395 0)
      (effects (font (size 1.27 1.27) (thickness 0.15)) (justify left bottom) hide)
    )
    (property "Manufacturer" "Bourns" (at 88.265 112.395 0)
      (effects (font (size 1.27 1.27) (thickness 0.15)) (justify left bottom) hide)
    )
    (property "MPN" "CR0402-FX-2201GLF" (at 90.805 112.395 0)
      (effects (font (size 1.27 1.27) (thickness 0.15)) (justify left bottom) hide)
    )
    (property "Val" "2k2" (at 113.03 96.5199 90)
      (effects (font (size 1.27 1.27) (thickness 0.15)) (justify left))
    )
    (property "License" "Apache-2.0" (at 85.725 112.395 0)
      (effects (font (size 1.27 1.27) (thickness 0.15)) (justify left bottom) hide)
    )
    (property "Author" "Antmicro" (at 83.185 112.395 0)
      (effects (font (size 1.27 1.27) (thickness 0.15)) (justify left bottom) hide)
    )
    (property "Tolerance" "1%" (at 100.965 112.395 0)
      (effects (font (size 1.27 1.27)) (justify left bottom) hide)
    )
    (pin "1")
    (pin "2")
    (instances
      (project "data-center-rdimm-ddr4-tester"
        (path ""
          (reference "R14") (unit 1)
        )
      )
    )
  )

  (symbol (lib_id "antmicroMicrocontrollers:XC7K160T-FFG676") (at 285.75 87.63 0) (unit 11)
    (in_bom yes) (on_board yes) (dnp no) (fields_autoplaced)
    (property "Reference" "U15" (at 304.8 80.01 0)
      (effects (font (size 1.27 1.27)))
    )
    (property "Value" "XC7K160T-FFG676" (at 304.8 82.55 0)
      (effects (font (size 1.27 1.27) (thickness 0.15)))
    )
    (property "Footprint" "antmicro-footprints:BGA-676_27x27mm_Layout26x26_P1X1mm" (at 354.33 90.17 0)
      (effects (font (size 1.27 1.27) (thickness 0.15)) (justify left bottom) hide)
    )
    (property "Datasheet" "https://docs.xilinx.com/v/u/en-US/ds180_7Series_Overview" (at 354.33 92.71 0)
      (effects (font (size 1.27 1.27) (thickness 0.15)) (justify left bottom) hide)
    )
    (property "MPN" "XC7K160T-FFG676" (at 285.75 87.63 0)
      (effects (font (size 1.27 1.27)) hide)
    )
    (property "Author" "Antmicro" (at 354.33 95.25 0)
      (effects (font (size 1.27 1.27) (thickness 0.15)) (justify left bottom) hide)
    )
    (property "License" "Apache-2.0" (at 354.33 97.79 0)
      (effects (font (size 1.27 1.27) (thickness 0.15)) (justify left bottom) hide)
    )
    (property "Manufacturer" "AMD-Xilinx" (at 285.75 87.63 0)
      (effects (font (size 1.27 1.27)) hide)
    )
    (pin "AA21")
    (pin "AA22")
    (pin "AA23")
    (pin "AA24")
    (pin "AA25")
    (pin "AB21")
    (pin "AB22")
    (pin "AB24")
    (pin "AB25")
    (pin "AB26")
    (pin "AC21")
    (pin "AC22")
    (pin "AC23")
    (pin "AC24")
    (pin "AC25")
    (pin "AC26")
    (pin "AD21")
    (pin "AD22")
    (pin "AD23")
    (pin "AD24")
    (pin "AD25")
    (pin "AD26")
    (pin "AE21")
    (pin "AE22")
    (pin "AE23")
    (pin "AE25")
    (pin "AE26")
    (pin "AF22")
    (pin "AF23")
    (pin "AF24")
    (pin "AF25")
    (pin "AF26")
    (pin "U21")
    (pin "U22")
    (pin "U23")
    (pin "U24")
    (pin "U25")
    (pin "U26")
    (pin "V20")
    (pin "V21")
    (pin "V22")
    (pin "V23")
    (pin "V24")
    (pin "V26")
    (pin "W20")
    (pin "W21")
    (pin "W23")
    (pin "W24")
    (pin "W25")
    (pin "W26")
    (pin "Y20")
    (pin "Y21")
    (pin "Y22")
    (pin "Y23")
    (pin "Y24")
    (pin "Y25")
    (pin "Y26")
    (pin "K24")
    (pin "K25")
    (pin "K26")
    (pin "L24")
    (pin "L25")
    (pin "M19")
    (pin "M20")
    (pin "M21")
    (pin "M22")
    (pin "M24")
    (pin "M25")
    (pin "M26")
    (pin "N16")
    (pin "N17")
    (pin "N18")
    (pin "N19")
    (pin "N21")
    (pin "N22")
    (pin "N23")
    (pin "N24")
    (pin "N25")
    (pin "N26")
    (pin "P16")
    (pin "P18")
    (pin "P19")
    (pin "P20")
    (pin "P21")
    (pin "P22")
    (pin "P23")
    (pin "P24")
    (pin "P25")
    (pin "P26")
    (pin "R16")
    (pin "R17")
    (pin "R18")
    (pin "R19")
    (pin "R20")
    (pin "R21")
    (pin "R22")
    (pin "R23")
    (pin "R25")
    (pin "R26")
    (pin "T16")
    (pin "T17")
    (pin "T18")
    (pin "T19")
    (pin "T20")
    (pin "T22")
    (pin "T23")
    (pin "T24")
    (pin "T25")
    (pin "T26")
    (pin "U16")
    (pin "U17")
    (pin "U19")
    (pin "U20")
    (pin "A20")
    (pin "A21")
    (pin "A22")
    (pin "A23")
    (pin "A24")
    (pin "A25")
    (pin "B20")
    (pin "B21")
    (pin "B22")
    (pin "B24")
    (pin "B25")
    (pin "B26")
    (pin "C21")
    (pin "C22")
    (pin "C23")
    (pin "C24")
    (pin "C25")
    (pin "C26")
    (pin "D21")
    (pin "D22")
    (pin "D23")
    (pin "D24")
    (pin "D25")
    (pin "D26")
    (pin "E21")
    (pin "E22")
    (pin "E23")
    (pin "E25")
    (pin "E26")
    (pin "F22")
    (pin "F23")
    (pin "F24")
    (pin "F25")
    (pin "F26")
    (pin "G21")
    (pin "G22")
    (pin "G23")
    (pin "G24")
    (pin "G25")
    (pin "G26")
    (pin "H21")
    (pin "H22")
    (pin "H23")
    (pin "H24")
    (pin "H26")
    (pin "J21")
    (pin "J23")
    (pin "J24")
    (pin "J25")
    (pin "J26")
    (pin "K21")
    (pin "K22")
    (pin "K23")
    (pin "L21")
    (pin "L22")
    (pin "L23")
    (pin "A17")
    (pin "A18")
    (pin "A19")
    (pin "B16")
    (pin "B17")
    (pin "B18")
    (pin "B19")
    (pin "C16")
    (pin "C17")
    (pin "C18")
    (pin "C19")
    (pin "D15")
    (pin "D16")
    (pin "D18")
    (pin "D19")
    (pin "D20")
    (pin "E15")
    (pin "E16")
    (pin "E17")
    (pin "E18")
    (pin "E19")
    (pin "E20")
    (pin "F15")
    (pin "F16")
    (pin "F17")
    (pin "F18")
    (pin "F19")
    (pin "F20")
    (pin "G15")
    (pin "G16")
    (pin "G17")
    (pin "G19")
    (pin "G20")
    (pin "H16")
    (pin "H17")
    (pin "H18")
    (pin "H19")
    (pin "H20")
    (pin "J15")
    (pin "J16")
    (pin "J17")
    (pin "J18")
    (pin "J19")
    (pin "J20")
    (pin "K15")
    (pin "K16")
    (pin "K17")
    (pin "K18")
    (pin "K20")
    (pin "L17")
    (pin "L18")
    (pin "L19")
    (pin "L20")
    (pin "M16")
    (pin "M17")
    (pin "M18")
    (pin "A10")
    (pin "A11")
    (pin "A12")
    (pin "A13")
    (pin "A14")
    (pin "A15")
    (pin "A8")
    (pin "A9")
    (pin "B10")
    (pin "B11")
    (pin "B12")
    (pin "B14")
    (pin "B15")
    (pin "B8")
    (pin "B9")
    (pin "C11")
    (pin "C12")
    (pin "C13")
    (pin "C14")
    (pin "C15")
    (pin "C9")
    (pin "D10")
    (pin "D11")
    (pin "D12")
    (pin "D13")
    (pin "D14")
    (pin "D8")
    (pin "D9")
    (pin "E10")
    (pin "E11")
    (pin "E12")
    (pin "E13")
    (pin "E9")
    (pin "F10")
    (pin "F12")
    (pin "F13")
    (pin "F14")
    (pin "F8")
    (pin "F9")
    (pin "G10")
    (pin "G11")
    (pin "G12")
    (pin "G13")
    (pin "G14")
    (pin "G9")
    (pin "H10")
    (pin "H11")
    (pin "H12")
    (pin "H13")
    (pin "H14")
    (pin "H8")
    (pin "H9")
    (pin "J10")
    (pin "J11")
    (pin "J13")
    (pin "J14")
    (pin "J8")
    (pin "AA14")
    (pin "AA15")
    (pin "AA17")
    (pin "AA18")
    (pin "AA19")
    (pin "AA20")
    (pin "AB14")
    (pin "AB15")
    (pin "AB16")
    (pin "AB17")
    (pin "AB18")
    (pin "AB19")
    (pin "AB20")
    (pin "AC14")
    (pin "AC15")
    (pin "AC16")
    (pin "AC17")
    (pin "AC18")
    (pin "AC19")
    (pin "AD14")
    (pin "AD15")
    (pin "AD16")
    (pin "AD18")
    (pin "AD19")
    (pin "AD20")
    (pin "AE15")
    (pin "AE16")
    (pin "AE17")
    (pin "AE18")
    (pin "AE19")
    (pin "AE20")
    (pin "AF14")
    (pin "AF15")
    (pin "AF16")
    (pin "AF17")
    (pin "AF18")
    (pin "AF19")
    (pin "AF20")
    (pin "V13")
    (pin "V14")
    (pin "V16")
    (pin "V17")
    (pin "V18")
    (pin "V19")
    (pin "W13")
    (pin "W14")
    (pin "W15")
    (pin "W16")
    (pin "W17")
    (pin "W18")
    (pin "W19")
    (pin "Y14")
    (pin "Y15")
    (pin "Y16")
    (pin "Y17")
    (pin "Y18")
    (pin "AA10")
    (pin "AA11")
    (pin "AA12")
    (pin "AA13")
    (pin "AA7")
    (pin "AA8")
    (pin "AA9")
    (pin "AB10")
    (pin "AB11")
    (pin "AB12")
    (pin "AB7")
    (pin "AB8")
    (pin "AB9")
    (pin "AC11")
    (pin "AC12")
    (pin "AC13")
    (pin "AC7")
    (pin "AC8")
    (pin "AC9")
    (pin "AD10")
    (pin "AD11")
    (pin "AD12")
    (pin "AD13")
    (pin "AD8")
    (pin "AD9")
    (pin "AE10")
    (pin "AE11")
    (pin "AE12")
    (pin "AE13")
    (pin "AE7")
    (pin "AE8")
    (pin "AE9")
    (pin "AF10")
    (pin "AF12")
    (pin "AF13")
    (pin "AF7")
    (pin "AF8")
    (pin "AF9")
    (pin "U9")
    (pin "V10")
    (pin "V11")
    (pin "V12")
    (pin "V7")
    (pin "V8")
    (pin "V9")
    (pin "W10")
    (pin "W11")
    (pin "W7")
    (pin "W8")
    (pin "W9")
    (pin "Y10")
    (pin "Y11")
    (pin "Y12")
    (pin "Y13")
    (pin "Y7")
    (pin "Y8")
    (pin "AA1")
    (pin "AA2")
    (pin "AA3")
    (pin "AA4")
    (pin "AA5")
    (pin "AB1")
    (pin "AB2")
    (pin "AB4")
    (pin "AB5")
    (pin "AB6")
    (pin "AC1")
    (pin "AC2")
    (pin "AC3")
    (pin "AC4")
    (pin "AC5")
    (pin "AC6")
    (pin "AD1")
    (pin "AD2")
    (pin "AD3")
    (pin "AD4")
    (pin "AD5")
    (pin "AD6")
    (pin "AE1")
    (pin "AE2")
    (pin "AE3")
    (pin "AE5")
    (pin "AE6")
    (pin "AF2")
    (pin "AF3")
    (pin "AF4")
    (pin "AF5")
    (pin "AF6")
    (pin "T7")
    (pin "U1")
    (pin "U2")
    (pin "U3")
    (pin "U4")
    (pin "U5")
    (pin "U6")
    (pin "U7")
    (pin "V1")
    (pin "V2")
    (pin "V3")
    (pin "V4")
    (pin "V6")
    (pin "W1")
    (pin "W3")
    (pin "W4")
    (pin "W5")
    (pin "W6")
    (pin "Y1")
    (pin "Y2")
    (pin "Y3")
    (pin "Y4")
    (pin "Y5")
    (pin "Y6")
    (pin "A3")
    (pin "A4")
    (pin "B1")
    (pin "B2")
    (pin "B5")
    (pin "B6")
    (pin "C3")
    (pin "C4")
    (pin "D1")
    (pin "D2")
    (pin "D5")
    (pin "D6")
    (pin "E3")
    (pin "E4")
    (pin "F1")
    (pin "F2")
    (pin "F5")
    (pin "F6")
    (pin "G3")
    (pin "G4")
    (pin "H1")
    (pin "H2")
    (pin "H5")
    (pin "H6")
    (pin "J3")
    (pin "J4")
    (pin "K1")
    (pin "K2")
    (pin "K5")
    (pin "K6")
    (pin "L3")
    (pin "L4")
    (pin "M1")
    (pin "M2")
    (pin "N3")
    (pin "N4")
    (pin "P1")
    (pin "P2")
    (pin "R3")
    (pin "R4")
    (pin "A1")
    (pin "A16")
    (pin "A2")
    (pin "A26")
    (pin "A5")
    (pin "A6")
    (pin "A7")
    (pin "AA16")
    (pin "AA26")
    (pin "AA6")
    (pin "AB13")
    (pin "AB23")
    (pin "AB3")
    (pin "AC10")
    (pin "AC20")
    (pin "AD17")
    (pin "AD7")
    (pin "AE14")
    (pin "AE24")
    (pin "AE4")
    (pin "AF1")
    (pin "AF11")
    (pin "AF21")
    (pin "B13")
    (pin "B23")
    (pin "B3")
    (pin "B4")
    (pin "B7")
    (pin "C1")
    (pin "C10")
    (pin "C2")
    (pin "C20")
    (pin "C5")
    (pin "C6")
    (pin "C7")
    (pin "D17")
    (pin "D3")
    (pin "D4")
    (pin "D7")
    (pin "E1")
    (pin "E14")
    (pin "E2")
    (pin "E24")
    (pin "E5")
    (pin "E6")
    (pin "E7")
    (pin "E8")
    (pin "F11")
    (pin "F21")
    (pin "F3")
    (pin "F4")
    (pin "F7")
    (pin "G1")
    (pin "G18")
    (pin "G2")
    (pin "G5")
    (pin "G6")
    (pin "G8")
    (pin "H15")
    (pin "H25")
    (pin "H3")
    (pin "H4")
    (pin "H7")
    (pin "J1")
    (pin "J12")
    (pin "J2")
    (pin "J22")
    (pin "J5")
    (pin "J6")
    (pin "J9")
    (pin "K10")
    (pin "K11")
    (pin "K12")
    (pin "K13")
    (pin "K14")
    (pin "K19")
    (pin "K3")
    (pin "K4")
    (pin "K7")
    (pin "K8")
    (pin "K9")
    (pin "L1")
    (pin "L10")
    (pin "L11")
    (pin "L12")
    (pin "L13")
    (pin "L14")
    (pin "L15")
    (pin "L16")
    (pin "L2")
    (pin "L26")
    (pin "L5")
    (pin "L6")
    (pin "L9")
    (pin "M10")
    (pin "M11")
    (pin "M12")
    (pin "M13")
    (pin "M14")
    (pin "M15")
    (pin "M23")
    (pin "M3")
    (pin "M4")
    (pin "M5")
    (pin "M6")
    (pin "M7")
    (pin "M8")
    (pin "M9")
    (pin "N1")
    (pin "N10")
    (pin "N13")
    (pin "N14")
    (pin "N15")
    (pin "N2")
    (pin "N20")
    (pin "N5")
    (pin "N6")
    (pin "N7")
    (pin "N9")
    (pin "P10")
    (pin "P13")
    (pin "P14")
    (pin "P15")
    (pin "P17")
    (pin "P3")
    (pin "P4")
    (pin "P8")
    (pin "P9")
    (pin "R1")
    (pin "R10")
    (pin "R13")
    (pin "R14")
    (pin "R15")
    (pin "R2")
    (pin "R24")
    (pin "R5")
    (pin "R8")
    (pin "R9")
    (pin "T1")
    (pin "T10")
    (pin "T11")
    (pin "T12")
    (pin "T13")
    (pin "T14")
    (pin "T15")
    (pin "T21")
    (pin "T3")
    (pin "T4")
    (pin "T8")
    (pin "T9")
    (pin "U10")
    (pin "U11")
    (pin "U12")
    (pin "U13")
    (pin "U14")
    (pin "U15")
    (pin "U18")
    (pin "U8")
    (pin "V15")
    (pin "V25")
    (pin "V5")
    (pin "W12")
    (pin "W2")
    (pin "W22")
    (pin "Y19")
    (pin "Y9")
    (pin "C8")
    (pin "G7")
    (pin "J7")
    (pin "L7")
    (pin "L8")
    (pin "N11")
    (pin "N12")
    (pin "N8")
    (pin "P11")
    (pin "P12")
    (pin "P5")
    (pin "P6")
    (pin "P7")
    (pin "R11")
    (pin "R12")
    (pin "R6")
    (pin "R7")
    (pin "T2")
    (pin "T5")
    (pin "T6")
    (instances
      (project "data-center-rdimm-ddr4-tester"
        (path ""
          (reference "U15") (unit 11)
        )
      )
    )
  )

  (symbol (lib_id "antmicropower:GND") (at 324.485 127.635 0) (mirror y) (unit 1)
    (in_bom yes) (on_board yes) (dnp no) (fields_autoplaced)
    (property "Reference" "#PWR0118" (at 324.485 133.985 0)
      (effects (font (size 1.27 1.27)) hide)
    )
    (property "Value" "GND" (at 324.485 132.715 0)
      (effects (font (size 1.27 1.27)))
    )
    (property "Footprint" "" (at 324.485 127.635 0)
      (effects (font (size 1.27 1.27)) hide)
    )
    (property "Datasheet" "" (at 324.485 127.635 0)
      (effects (font (size 1.27 1.27)) hide)
    )
    (property "Author" "Antmicro" (at 315.595 135.255 0)
      (effects (font (size 1.27 1.27) (thickness 0.15)) (justify left bottom) hide)
    )
    (property "License" "Apache-2.0" (at 315.595 137.795 0)
      (effects (font (size 1.27 1.27) (thickness 0.15)) (justify left bottom) hide)
    )
    (pin "1")
    (instances
      (project "data-center-rdimm-ddr4-tester"
        (path ""
          (reference "#PWR0118") (unit 1)
        )
      )
    )
  )

  (symbol (lib_id "antmicroResistors0402:R_4k7_0402") (at 244.475 108.585 270) (unit 1)
    (in_bom yes) (on_board yes) (dnp no)
    (property "Reference" "R28" (at 246.38 109.8551 90)
      (effects (font (size 1.524 1.524)) (justify left))
    )
    (property "Value" "R_4k7_0402" (at 231.775 128.905 0)
      (effects (font (size 1.27 1.27) (thickness 0.15)) (justify left bottom) hide)
    )
    (property "Footprint" "antmicro-footprints:R_0402_1005Metric" (at 229.235 128.905 0)
      (effects (font (size 1.27 1.27) (thickness 0.15)) (justify left bottom) hide)
    )
    (property "Datasheet" "https://www.bourns.com/docs/product-datasheets/cr.pdf" (at 226.695 128.905 0)
      (effects (font (size 1.27 1.27) (thickness 0.15)) (justify left bottom) hide)
    )
    (property "Manufacturer" "Bourns" (at 221.615 128.905 0)
      (effects (font (size 1.27 1.27) (thickness 0.15)) (justify left bottom) hide)
    )
    (property "MPN" "CR0402-FX-4701GLF" (at 224.155 128.905 0)
      (effects (font (size 1.27 1.27) (thickness 0.15)) (justify left bottom) hide)
    )
    (property "Val" "4k7" (at 246.38 113.03 90)
      (effects (font (size 1.27 1.27) (thickness 0.15)) (justify left))
    )
    (property "License" "Apache-2.0" (at 219.075 128.905 0)
      (effects (font (size 1.27 1.27) (thickness 0.15)) (justify left bottom) hide)
    )
    (property "Author" "Antmicro" (at 216.535 128.905 0)
      (effects (font (size 1.27 1.27) (thickness 0.15)) (justify left bottom) hide)
    )
    (property "Tolerance" "1%" (at 234.315 128.905 0)
      (effects (font (size 1.27 1.27)) (justify left bottom) hide)
    )
    (pin "1")
    (pin "2")
    (instances
      (project "data-center-rdimm-ddr4-tester"
        (path ""
          (reference "R28") (unit 1)
        )
      )
    )
  )

  (symbol (lib_id "antmicropower:GND") (at 118.11 122.555 0) (unit 1)
    (in_bom yes) (on_board yes) (dnp no) (fields_autoplaced)
    (property "Reference" "#PWR0119" (at 118.11 128.905 0)
      (effects (font (size 1.27 1.27)) hide)
    )
    (property "Value" "GND" (at 118.11 127.635 0)
      (effects (font (size 1.27 1.27)))
    )
    (property "Footprint" "" (at 118.11 122.555 0)
      (effects (font (size 1.27 1.27)) hide)
    )
    (property "Datasheet" "" (at 118.11 122.555 0)
      (effects (font (size 1.27 1.27)) hide)
    )
    (property "Author" "Antmicro" (at 127 130.175 0)
      (effects (font (size 1.27 1.27) (thickness 0.15)) (justify left bottom) hide)
    )
    (property "License" "Apache-2.0" (at 127 132.715 0)
      (effects (font (size 1.27 1.27) (thickness 0.15)) (justify left bottom) hide)
    )
    (pin "1")
    (instances
      (project "data-center-rdimm-ddr4-tester"
        (path ""
          (reference "#PWR0119") (unit 1)
        )
      )
    )
  )

  (symbol (lib_id "antmicroCapacitors0603:C_47u_0603") (at 363.22 94.615 270) (unit 1)
    (in_bom yes) (on_board yes) (dnp no)
    (property "Reference" "C12" (at 363.855 95.25 90)
      (effects (font (size 1.524 1.524)) (justify left))
    )
    (property "Value" "C_47u_0603" (at 353.06 114.935 0)
      (effects (font (size 1.27 1.27) (thickness 0.15)) (justify left bottom) hide)
    )
    (property "Footprint" "antmicro-footprints:C_0603_1608Metric" (at 350.52 114.935 0)
      (effects (font (size 1.27 1.27) (thickness 0.15)) (justify left bottom) hide)
    )
    (property "Datasheet" " " (at 347.98 114.935 0)
      (effects (font (size 1.27 1.27) (thickness 0.15)) (justify left bottom) hide)
    )
    (property "Manufacturer" "Murata" (at 342.9 114.935 0)
      (effects (font (size 1.27 1.27) (thickness 0.15)) (justify left bottom) hide)
    )
    (property "MPN" "GRM188R60J476ME15D" (at 345.44 114.935 0)
      (effects (font (size 1.27 1.27) (thickness 0.15)) (justify left bottom) hide)
    )
    (property "Val" "47u" (at 363.855 99.06 90)
      (effects (font (size 1.27 1.27) (thickness 0.15)) (justify left))
    )
    (property "License" "Apache-2.0" (at 340.36 114.935 0)
      (effects (font (size 1.27 1.27) (thickness 0.15)) (justify left bottom) hide)
    )
    (property "Author" "Antmicro" (at 337.82 114.935 0)
      (effects (font (size 1.27 1.27) (thickness 0.15)) (justify left bottom) hide)
    )
    (property "Voltage" "" (at 335.28 114.935 0)
      (effects (font (size 1.27 1.27)) (justify left bottom) hide)
    )
    (property "Dielectric" "" (at 332.74 114.935 0)
      (effects (font (size 1.27 1.27)) (justify left bottom) hide)
    )
    (pin "1")
    (pin "2")
    (instances
      (project "data-center-rdimm-ddr4-tester"
        (path ""
          (reference "C12") (unit 1)
        )
      )
    )
  )

  (symbol (lib_id "antmicroCapacitors0402:C_470n_0402") (at 371.475 94.615 270) (unit 1)
    (in_bom yes) (on_board yes) (dnp no)
    (property "Reference" "C13" (at 372.11 95.25 90)
      (effects (font (size 1.524 1.524)) (justify left))
    )
    (property "Value" "C_470n_0402" (at 361.315 114.935 0)
      (effects (font (size 1.27 1.27) (thickness 0.15)) (justify left bottom) hide)
    )
    (property "Footprint" "antmicro-footprints:C_0402_1005Metric" (at 358.775 114.935 0)
      (effects (font (size 1.27 1.27) (thickness 0.15)) (justify left bottom) hide)
    )
    (property "Datasheet" " " (at 356.235 114.935 0)
      (effects (font (size 1.27 1.27) (thickness 0.15)) (justify left bottom) hide)
    )
    (property "Manufacturer" "TDK" (at 351.155 114.935 0)
      (effects (font (size 1.27 1.27) (thickness 0.15)) (justify left bottom) hide)
    )
    (property "MPN" "C1005X5R1E474M050BB" (at 353.695 114.935 0)
      (effects (font (size 1.27 1.27) (thickness 0.15)) (justify left bottom) hide)
    )
    (property "Val" "470n" (at 372.11 99.06 90)
      (effects (font (size 1.27 1.27) (thickness 0.15)) (justify left))
    )
    (property "License" "Apache-2.0" (at 348.615 114.935 0)
      (effects (font (size 1.27 1.27) (thickness 0.15)) (justify left bottom) hide)
    )
    (property "Author" "Antmicro" (at 346.075 114.935 0)
      (effects (font (size 1.27 1.27) (thickness 0.15)) (justify left bottom) hide)
    )
    (property "Voltage" "" (at 343.535 114.935 0)
      (effects (font (size 1.27 1.27)) (justify left bottom) hide)
    )
    (property "Dielectric" "" (at 340.995 114.935 0)
      (effects (font (size 1.27 1.27)) (justify left bottom) hide)
    )
    (pin "1")
    (pin "2")
    (instances
      (project "data-center-rdimm-ddr4-tester"
        (path ""
          (reference "C13") (unit 1)
        )
      )
    )
  )

  (symbol (lib_id "antmicropower:GND") (at 363.22 104.14 0) (unit 1)
    (in_bom yes) (on_board yes) (dnp no) (fields_autoplaced)
    (property "Reference" "#PWR0120" (at 363.22 110.49 0)
      (effects (font (size 1.27 1.27)) hide)
    )
    (property "Value" "GND" (at 363.22 108.585 0)
      (effects (font (size 1.27 1.27)))
    )
    (property "Footprint" "" (at 363.22 104.14 0)
      (effects (font (size 1.27 1.27)) hide)
    )
    (property "Datasheet" "" (at 363.22 104.14 0)
      (effects (font (size 1.27 1.27)) hide)
    )
    (property "Author" "Antmicro" (at 372.11 111.76 0)
      (effects (font (size 1.27 1.27) (thickness 0.15)) (justify left bottom) hide)
    )
    (property "License" "Apache-2.0" (at 372.11 114.3 0)
      (effects (font (size 1.27 1.27) (thickness 0.15)) (justify left bottom) hide)
    )
    (pin "1")
    (instances
      (project "data-center-rdimm-ddr4-tester"
        (path ""
          (reference "#PWR0120") (unit 1)
        )
      )
    )
  )

  (symbol (lib_id "antmicroTestPoints:TP_1mm_SMD") (at 324.104 228.854 180) (unit 1)
    (in_bom yes) (on_board yes) (dnp no) (fields_autoplaced)
    (property "Reference" "PUDC_B1" (at 320.929 225.806 0)
      (effects (font (size 1.27 1.27)))
    )
    (property "Value" "TP_1mm_SMD" (at 308.864 221.234 0)
      (effects (font (size 1.27 1.27) (thickness 0.15)) (justify left bottom) hide)
    )
    (property "Footprint" "antmicro-footprints:TP_SMD_1mm" (at 308.864 218.694 0)
      (effects (font (size 1.27 1.27) (thickness 0.15)) (justify left bottom) hide)
    )
    (property "Datasheet" "" (at 308.864 216.154 0)
      (effects (font (size 1.27 1.27) (thickness 0.15)) (justify left bottom) hide)
    )
    (property "MPN" "" (at 324.104 228.854 0)
      (effects (font (size 1.27 1.27)) hide)
    )
    (property "Manufacturer" "" (at 324.104 228.854 0)
      (effects (font (size 1.27 1.27)) hide)
    )
    (property "Author" "Antmicro" (at 308.864 213.614 0)
      (effects (font (size 1.27 1.27) (thickness 0.15)) (justify left bottom) hide)
    )
    (property "License" "Apache-2.0" (at 308.864 211.074 0)
      (effects (font (size 1.27 1.27) (thickness 0.15)) (justify left bottom) hide)
    )
    (pin "1")
    (instances
      (project "data-center-rdimm-ddr4-tester"
        (path ""
          (reference "PUDC_B1") (unit 1)
        )
      )
    )
  )

  (symbol (lib_id "antmicroTestPoints:TP_1mm_SMD") (at 365.76 228.854 180) (unit 1)
    (in_bom yes) (on_board yes) (dnp no) (fields_autoplaced)
    (property "Reference" "EMCCLK1" (at 362.585 226.06 0)
      (effects (font (size 1.27 1.27)))
    )
    (property "Value" "TP_1mm_SMD" (at 350.52 221.234 0)
      (effects (font (size 1.27 1.27) (thickness 0.15)) (justify left bottom) hide)
    )
    (property "Footprint" "antmicro-footprints:TP_SMD_1mm" (at 350.52 218.694 0)
      (effects (font (size 1.27 1.27) (thickness 0.15)) (justify left bottom) hide)
    )
    (property "Datasheet" "" (at 350.52 216.154 0)
      (effects (font (size 1.27 1.27) (thickness 0.15)) (justify left bottom) hide)
    )
    (property "MPN" "" (at 365.76 228.854 0)
      (effects (font (size 1.27 1.27)) hide)
    )
    (property "Manufacturer" "" (at 365.76 228.854 0)
      (effects (font (size 1.27 1.27)) hide)
    )
    (property "Author" "Antmicro" (at 350.52 213.614 0)
      (effects (font (size 1.27 1.27) (thickness 0.15)) (justify left bottom) hide)
    )
    (property "License" "Apache-2.0" (at 350.52 211.074 0)
      (effects (font (size 1.27 1.27) (thickness 0.15)) (justify left bottom) hide)
    )
    (pin "1")
    (instances
      (project "data-center-rdimm-ddr4-tester"
        (path ""
          (reference "EMCCLK1") (unit 1)
        )
      )
    )
  )

  (symbol (lib_id "antmicroCapacitors0402:C_100n_0402") (at 50.165 106.045 90) (mirror x) (unit 1)
    (in_bom yes) (on_board yes) (dnp no) (fields_autoplaced)
    (property "Reference" "C5" (at 52.705 107.3213 90)
      (effects (font (size 1.524 1.524)) (justify right))
    )
    (property "Value" "C_100n_0402" (at 60.325 126.365 0)
      (effects (font (size 1.27 1.27) (thickness 0.15)) (justify left bottom) hide)
    )
    (property "Footprint" "antmicro-footprints:C_0402_1005Metric" (at 62.865 126.365 0)
      (effects (font (size 1.27 1.27) (thickness 0.15)) (justify left bottom) hide)
    )
    (property "Datasheet" "https://search.murata.co.jp/Ceramy/image/img/A01X/G101/ENG/GRM155R61H104KE14-01.pdf" (at 65.405 126.365 0)
      (effects (font (size 1.27 1.27) (thickness 0.15)) (justify left bottom) hide)
    )
    (property "Manufacturer" "Murata" (at 70.485 126.365 0)
      (effects (font (size 1.27 1.27) (thickness 0.15)) (justify left bottom) hide)
    )
    (property "MPN" "GRM155R61H104KE14D" (at 67.945 126.365 0)
      (effects (font (size 1.27 1.27) (thickness 0.15)) (justify left bottom) hide)
    )
    (property "Val" "100n" (at 52.705 110.4962 90)
      (effects (font (size 1.27 1.27) (thickness 0.15)) (justify right))
    )
    (property "License" "Apache-2.0" (at 73.025 126.365 0)
      (effects (font (size 1.27 1.27) (thickness 0.15)) (justify left bottom) hide)
    )
    (property "Author" "Antmicro" (at 75.565 126.365 0)
      (effects (font (size 1.27 1.27) (thickness 0.15)) (justify left bottom) hide)
    )
    (property "Voltage" "50V" (at 78.105 126.365 0)
      (effects (font (size 1.27 1.27)) (justify left bottom) hide)
    )
    (property "Dielectric" "X5R" (at 80.645 126.365 0)
      (effects (font (size 1.27 1.27)) (justify left bottom) hide)
    )
    (pin "1")
    (pin "2")
    (instances
      (project "data-center-rdimm-ddr4-tester"
        (path ""
          (reference "C5") (unit 1)
        )
      )
    )
  )

  (symbol (lib_id "antmicropower:GND") (at 50.165 111.125 0) (unit 1)
    (in_bom yes) (on_board yes) (dnp no) (fields_autoplaced)
    (property "Reference" "#PWR0132" (at 50.165 117.475 0)
      (effects (font (size 1.27 1.27)) hide)
    )
    (property "Value" "GND" (at 50.165 116.205 0)
      (effects (font (size 1.27 1.27)))
    )
    (property "Footprint" "" (at 50.165 111.125 0)
      (effects (font (size 1.27 1.27)) hide)
    )
    (property "Datasheet" "" (at 50.165 111.125 0)
      (effects (font (size 1.27 1.27)) hide)
    )
    (property "Author" "Antmicro" (at 59.055 118.745 0)
      (effects (font (size 1.27 1.27) (thickness 0.15)) (justify left bottom) hide)
    )
    (property "License" "Apache-2.0" (at 59.055 121.285 0)
      (effects (font (size 1.27 1.27) (thickness 0.15)) (justify left bottom) hide)
    )
    (pin "1")
    (instances
      (project "data-center-rdimm-ddr4-tester"
        (path ""
          (reference "#PWR0132") (unit 1)
        )
      )
    )
  )

  (symbol (lib_id "antmicroGenericPinHeaders:PinHeader_2x7_P2mm_SMD_Shrouded_no-locator") (at 40.005 227.33 0) (unit 1)
    (in_bom no) (on_board yes) (dnp yes)
    (property "Reference" "J1" (at 45.085 221.615 0)
      (effects (font (size 1.27 1.27)))
    )
    (property "Value" "PinHeader_2x7_P2mm_SMD_Shrouded_no-locator" (at 65.405 232.41 0)
      (effects (font (size 1.27 1.27) (thickness 0.15)) (justify left bottom) hide)
    )
    (property "Footprint" "antmicro-footprints:PinHeader_2x7_P2mm_SMD_Shrouded_no-locator" (at 65.405 234.95 0)
      (effects (font (size 1.27 1.27) (thickness 0.15)) (justify left bottom) hide)
    )
    (property "Datasheet" "https://www.molex.com/pdm_docs/ps/PS-87831-027-001.pdf" (at 65.405 237.49 0)
      (effects (font (size 1.27 1.27) (thickness 0.15)) (justify left bottom) hide)
    )
    (property "MPN" "878321412" (at 45.085 224.155 0)
      (effects (font (size 1.27 1.27) (thickness 0.15)))
    )
    (property "Manufacturer" "Molex" (at 65.405 242.57 0)
      (effects (font (size 1.27 1.27) (thickness 0.15)) (justify left bottom) hide)
    )
    (property "Author" "Antmicro" (at 65.405 245.11 0)
      (effects (font (size 1.27 1.27) (thickness 0.15)) (justify left bottom) hide)
    )
    (property "License" "Apache-2.0" (at 65.405 247.65 0)
      (effects (font (size 1.27 1.27) (thickness 0.15)) (justify left bottom) hide)
    )
    (property "DNP" "DNP" (at 45.085 245.745 0)
      (effects (font (size 1.27 1.27)))
    )
    (pin "1")
    (pin "10")
    (pin "11")
    (pin "12")
    (pin "13")
    (pin "14")
    (pin "2")
    (pin "3")
    (pin "4")
    (pin "5")
    (pin "6")
    (pin "7")
    (pin "8")
    (pin "9")
    (instances
      (project "data-center-rdimm-ddr4-tester"
        (path ""
          (reference "J1") (unit 1)
        )
      )
    )
  )

  (symbol (lib_id "antmicroResistors0402:R_10k_0402") (at 226.06 259.08 90) (unit 1)
    (in_bom yes) (on_board yes) (dnp no) (fields_autoplaced)
    (property "Reference" "R193" (at 228.6 255.27 90)
      (effects (font (size 1.524 1.524)) (justify right))
    )
    (property "Value" "R_10k_0402" (at 238.76 238.76 0)
      (effects (font (size 1.27 1.27) (thickness 0.15)) (justify left bottom) hide)
    )
    (property "Footprint" "antmicro-footprints:R_0402_1005Metric" (at 241.3 238.76 0)
      (effects (font (size 1.27 1.27) (thickness 0.15)) (justify left bottom) hide)
    )
    (property "Datasheet" "https://www.bourns.com/docs/product-datasheets/cr.pdf" (at 243.84 238.76 0)
      (effects (font (size 1.27 1.27) (thickness 0.15)) (justify left bottom) hide)
    )
    (property "Manufacturer" "Bourns" (at 248.92 238.76 0)
      (effects (font (size 1.27 1.27) (thickness 0.15)) (justify left bottom) hide)
    )
    (property "MPN" "CR0402-FX-1002GLF" (at 246.38 238.76 0)
      (effects (font (size 1.27 1.27) (thickness 0.15)) (justify left bottom) hide)
    )
    (property "Val" "10k" (at 228.6 258.4449 90)
      (effects (font (size 1.27 1.27) (thickness 0.15)) (justify right))
    )
    (property "License" "Apache-2.0" (at 251.46 238.76 0)
      (effects (font (size 1.27 1.27) (thickness 0.15)) (justify left bottom) hide)
    )
    (property "Author" "Antmicro" (at 254 238.76 0)
      (effects (font (size 1.27 1.27) (thickness 0.15)) (justify left bottom) hide)
    )
    (property "Tolerance" "1%" (at 236.22 238.76 0)
      (effects (font (size 1.27 1.27)) (justify left bottom) hide)
    )
    (pin "1")
    (pin "2")
    (instances
      (project "data-center-rdimm-ddr4-tester"
        (path ""
          (reference "R193") (unit 1)
        )
      )
    )
  )

  (symbol (lib_id "antmicroSlideSwitches:SW_DS04-254-1-01BK-SMT") (at 233.68 262.89 0) (unit 1)
    (in_bom yes) (on_board yes) (dnp no)
    (property "Reference" "S2" (at 237.49 257.175 0)
      (effects (font (size 1.27 1.27)))
    )
    (property "Value" "SW_DS04-254-1-01BK-SMT" (at 240.03 257.81 0)
      (effects (font (size 1.27 1.27) (thickness 0.15)) hide)
    )
    (property "Footprint" "antmicro-footprints:SW_DS04-254-1-01BK-SMT" (at 260.35 270.51 0)
      (effects (font (size 1.27 1.27) (thickness 0.15)) (justify left bottom) hide)
    )
    (property "Datasheet" "https://www.mouser.com/datasheet/2/670/ds04_254_smt-1777718.pdf" (at 260.35 273.05 0)
      (effects (font (size 1.27 1.27) (thickness 0.15)) (justify left bottom) hide)
    )
    (property "MPN" "DS04-254-1-01BK-SMT" (at 236.22 259.08 0)
      (effects (font (size 1.27 1.27) (thickness 0.15)) (justify left))
    )
    (property "Manufacturer" "CUI Inc" (at 260.35 278.13 0)
      (effects (font (size 1.27 1.27) (thickness 0.15)) (justify left bottom) hide)
    )
    (property "Author" "Antmicro" (at 260.35 280.67 0)
      (effects (font (size 1.27 1.27) (thickness 0.15)) (justify left bottom) hide)
    )
    (property "License" "Apache-2.0" (at 260.35 283.21 0)
      (effects (font (size 1.27 1.27) (thickness 0.15)) (justify left bottom) hide)
    )
    (pin "1")
    (pin "2")
    (instances
      (project "data-center-rdimm-ddr4-tester"
        (path ""
          (reference "S2") (unit 1)
        )
      )
    )
  )
)
